(kicad_sch 
    (version 20211123) 
    (generator eeschema) 
    (paper "A3") 
    (title_block 
        (title "SI test board") 
        (date "2023-11-03") 
        (rev "1.0.1") 
        (comment 1 "www.antmicro.com") 
        (comment 2 "Antmicro")) 
    (junction 
        (at 168.275 149.86) 
        (diameter 0) 
        (color 0 0 0 0) 
       ) 
    (junction 
        (at 168.275 126.365) 
        (diameter 0) 
        (color 0 0 0 0) 
       ) 
    (no_connect 
        (at 226.695 76.2) 
       ) 
    (no_connect 
        (at 168.275 215.265) 
       ) 
    (no_connect 
        (at 173.355 213.995) 
       ) 
    (no_connect 
        (at 178.435 215.265) 
       ) 
    (no_connect 
        (at 196.215 74.295) 
       ) 
    (no_connect 
        (at 156.845 74.295) 
       ) 
    (wire 
        (pts 
            (xy 128.27 75.565) 
            (xy 128.27 82.55)) 
        (stroke 
            (width 0) 
            (type default) 
            (color 0 0 0 0)) 
       ) 
    (wire 
        (pts 
            (xy 160.655 60.325) 
            (xy 160.655 62.865)) 
        (stroke 
            (width 0) 
            (type default) 
            (color 0 0 0 0)) 
       ) 
    (wire 
        (pts 
            (xy 184.15 233.68) 
            (xy 179.07 233.68)) 
        (stroke 
            (width 0) 
            (type default) 
            (color 0 0 0 0)) 
       ) 
    (polyline 
        (pts 
            (xy 213.995 64.135) 
            (xy 266.065 64.135)) 
        (stroke 
            (width 0) 
            (type default) 
            (color 0 0 0 0)) 
       ) 
    (wire 
        (pts 
            (xy 160.655 65.405) 
            (xy 160.655 67.945)) 
        (stroke 
            (width 0) 
            (type default) 
            (color 0 0 0 0)) 
       ) 
    (wire 
        (pts 
            (xy 189.23 110.49) 
            (xy 189.23 112.395)) 
        (stroke 
            (width 0) 
            (type default) 
            (color 0 0 0 0)) 
       ) 
    (wire 
        (pts 
            (xy 165.735 189.23) 
            (xy 164.465 189.23)) 
        (stroke 
            (width 0) 
            (type default) 
            (color 0 0 0 0)) 
       ) 
    (wire 
        (pts 
            (xy 160.655 72.39) 
            (xy 156.845 72.39)) 
        (stroke 
            (width 0) 
            (type default) 
            (color 0 0 0 0)) 
       ) 
    (wire 
        (pts 
            (xy 173.355 213.995) 
            (xy 173.355 219.075)) 
        (stroke 
            (width 0) 
            (type default) 
            (color 0 0 0 0)) 
       ) 
    (wire 
        (pts 
            (xy 226.695 76.2) 
            (xy 230.505 76.2)) 
        (stroke 
            (width 0) 
            (type default) 
            (color 0 0 0 0)) 
       ) 
    (wire 
        (pts 
            (xy 164.465 149.86) 
            (xy 168.275 149.86)) 
        (stroke 
            (width 0) 
            (type default) 
            (color 0 0 0 0)) 
       ) 
    (wire 
        (pts 
            (xy 189.23 194.31) 
            (xy 189.23 196.215)) 
        (stroke 
            (width 0) 
            (type default) 
            (color 0 0 0 0)) 
       ) 
    (polyline 
        (pts 
            (xy 80.645 30.48) 
            (xy 80.645 273.05)) 
        (stroke 
            (width 0) 
            (type default) 
            (color 0 0 0 0)) 
       ) 
    (wire 
        (pts 
            (xy 189.23 131.445) 
            (xy 189.23 133.35)) 
        (stroke 
            (width 0) 
            (type default) 
            (color 0 0 0 0)) 
       ) 
    (wire 
        (pts 
            (xy 160.655 62.865) 
            (xy 153.67 62.865)) 
        (stroke 
            (width 0) 
            (type default) 
            (color 0 0 0 0)) 
       ) 
    (wire 
        (pts 
            (xy 184.15 212.09) 
            (xy 182.88 212.09)) 
        (stroke 
            (width 0) 
            (type default) 
            (color 0 0 0 0)) 
       ) 
    (wire 
        (pts 
            (xy 111.125 80.645) 
            (xy 111.125 82.55)) 
        (stroke 
            (width 0) 
            (type default) 
            (color 0 0 0 0)) 
       ) 
    (wire 
        (pts 
            (xy 179.07 258.445) 
            (xy 179.07 255.27)) 
        (stroke 
            (width 0) 
            (type default) 
            (color 0 0 0 0)) 
       ) 
    (wire 
        (pts 
            (xy 200.025 61.595) 
            (xy 200.025 62.23)) 
        (stroke 
            (width 0) 
            (type default) 
            (color 0 0 0 0)) 
       ) 
    (wire 
        (pts 
            (xy 158.75 260.35) 
            (xy 158.75 268.224)) 
        (stroke 
            (width 0) 
            (type default) 
            (color 0 0 0 0)) 
       ) 
    (wire 
        (pts 
            (xy 193.04 62.23) 
            (xy 193.04 62.865)) 
        (stroke 
            (width 0) 
            (type default) 
            (color 0 0 0 0)) 
       ) 
    (wire 
        (pts 
            (xy 165.735 185.42) 
            (xy 182.88 185.42)) 
        (stroke 
            (width 0) 
            (type default) 
            (color 0 0 0 0)) 
       ) 
    (wire 
        (pts 
            (xy 182.88 180.34) 
            (xy 184.15 180.34)) 
        (stroke 
            (width 0) 
            (type default) 
            (color 0 0 0 0)) 
       ) 
    (wire 
        (pts 
            (xy 200.025 62.865) 
            (xy 200.025 63.5)) 
        (stroke 
            (width 0) 
            (type default) 
            (color 0 0 0 0)) 
       ) 
    (wire 
        (pts 
            (xy 184.15 126.365) 
            (xy 168.275 126.365)) 
        (stroke 
            (width 0) 
            (type default) 
            (color 0 0 0 0)) 
       ) 
    (wire 
        (pts 
            (xy 179.07 233.68) 
            (xy 179.07 236.855)) 
        (stroke 
            (width 0) 
            (type default) 
            (color 0 0 0 0)) 
       ) 
    (wire 
        (pts 
            (xy 164.465 180.34) 
            (xy 165.735 180.34)) 
        (stroke 
            (width 0) 
            (type default) 
            (color 0 0 0 0)) 
       ) 
    (wire 
        (pts 
            (xy 203.2 50.8) 
            (xy 201.295 50.8)) 
        (stroke 
            (width 0) 
            (type default) 
            (color 0 0 0 0)) 
       ) 
    (wire 
        (pts 
            (xy 168.275 149.86) 
            (xy 168.275 153.67)) 
        (stroke 
            (width 0) 
            (type default) 
            (color 0 0 0 0)) 
       ) 
    (wire 
        (pts 
            (xy 159.385 175.26) 
            (xy 159.385 173.355)) 
        (stroke 
            (width 0) 
            (type default) 
            (color 0 0 0 0)) 
       ) 
    (wire 
        (pts 
            (xy 165.735 180.34) 
            (xy 165.735 184.15)) 
        (stroke 
            (width 0) 
            (type default) 
            (color 0 0 0 0)) 
       ) 
    (wire 
        (pts 
            (xy 159.385 154.94) 
            (xy 159.385 156.845)) 
        (stroke 
            (width 0) 
            (type default) 
            (color 0 0 0 0)) 
       ) 
    (polyline 
        (pts 
            (xy 80.01 224.155) 
            (xy 266.065 224.155)) 
        (stroke 
            (width 0) 
            (type default) 
            (color 0 0 0 0)) 
       ) 
    (wire 
        (pts 
            (xy 184.15 189.23) 
            (xy 182.88 189.23)) 
        (stroke 
            (width 0) 
            (type default) 
            (color 0 0 0 0)) 
       ) 
    (polyline 
        (pts 
            (xy 137.795 31.75) 
            (xy 137.795 93.345)) 
        (stroke 
            (width 0) 
            (type default) 
            (color 0 0 0 0)) 
       ) 
    (wire 
        (pts 
            (xy 158.75 217.17) 
            (xy 158.75 219.075)) 
        (stroke 
            (width 0) 
            (type default) 
            (color 0 0 0 0)) 
       ) 
    (wire 
        (pts 
            (xy 200.025 62.23) 
            (xy 193.04 62.23)) 
        (stroke 
            (width 0) 
            (type default) 
            (color 0 0 0 0)) 
       ) 
    (wire 
        (pts 
            (xy 171.45 153.67) 
            (xy 168.275 153.67)) 
        (stroke 
            (width 0) 
            (type default) 
            (color 0 0 0 0)) 
       ) 
    (wire 
        (pts 
            (xy 196.215 63.5) 
            (xy 196.215 74.295)) 
        (stroke 
            (width 0) 
            (type default) 
            (color 0 0 0 0)) 
       ) 
    (wire 
        (pts 
            (xy 193.04 61.595) 
            (xy 200.025 61.595)) 
        (stroke 
            (width 0) 
            (type default) 
            (color 0 0 0 0)) 
       ) 
    (wire 
        (pts 
            (xy 156.845 72.39) 
            (xy 156.845 74.295)) 
        (stroke 
            (width 0) 
            (type default) 
            (color 0 0 0 0)) 
       ) 
    (wire 
        (pts 
            (xy 193.04 59.69) 
            (xy 193.04 60.325)) 
        (stroke 
            (width 0) 
            (type default) 
            (color 0 0 0 0)) 
       ) 
    (polyline 
        (pts 
            (xy 80.645 64.135) 
            (xy 137.795 64.135)) 
        (stroke 
            (width 0) 
            (type default) 
            (color 0 0 0 0)) 
       ) 
    (polyline 
        (pts 
            (xy 80.01 141.605) 
            (xy 266.065 141.605)) 
        (stroke 
            (width 0) 
            (type default) 
            (color 0 0 0 0)) 
       ) 
    (wire 
        (pts 
            (xy 184.15 255.27) 
            (xy 179.07 255.27)) 
        (stroke 
            (width 0) 
            (type default) 
            (color 0 0 0 0)) 
       ) 
    (wire 
        (pts 
            (xy 182.88 212.09) 
            (xy 182.88 219.075)) 
        (stroke 
            (width 0) 
            (type default) 
            (color 0 0 0 0)) 
       ) 
    (wire 
        (pts 
            (xy 116.205 75.565) 
            (xy 128.27 75.565)) 
        (stroke 
            (width 0) 
            (type default) 
            (color 0 0 0 0)) 
       ) 
    (wire 
        (pts 
            (xy 168.275 210.185) 
            (xy 168.275 215.265)) 
        (stroke 
            (width 0) 
            (type default) 
            (color 0 0 0 0)) 
       ) 
    (wire 
        (pts 
            (xy 193.04 60.325) 
            (xy 200.025 60.325)) 
        (stroke 
            (width 0) 
            (type default) 
            (color 0 0 0 0)) 
       ) 
    (wire 
        (pts 
            (xy 153.67 70.485) 
            (xy 160.655 70.485)) 
        (stroke 
            (width 0) 
            (type default) 
            (color 0 0 0 0)) 
       ) 
    (wire 
        (pts 
            (xy 166.37 233.68) 
            (xy 166.37 236.855)) 
        (stroke 
            (width 0) 
            (type default) 
            (color 0 0 0 0)) 
       ) 
    (wire 
        (pts 
            (xy 113.665 49.53) 
            (xy 115.57 49.53)) 
        (stroke 
            (width 0) 
            (type default) 
            (color 0 0 0 0)) 
       ) 
    (wire 
        (pts 
            (xy 182.88 131.445) 
            (xy 183.515 131.445)) 
        (stroke 
            (width 0) 
            (type default) 
            (color 0 0 0 0)) 
       ) 
    (polyline 
        (pts 
            (xy 80.01 93.345) 
            (xy 266.065 93.98)) 
        (stroke 
            (width 0) 
            (type default) 
            (color 0 0 0 0)) 
       ) 
    (wire 
        (pts 
            (xy 168.275 131.445) 
            (xy 177.8 131.445)) 
        (stroke 
            (width 0) 
            (type default) 
            (color 0 0 0 0)) 
       ) 
    (wire 
        (pts 
            (xy 235.585 50.8) 
            (xy 235.585 52.705)) 
        (stroke 
            (width 0) 
            (type default) 
            (color 0 0 0 0)) 
       ) 
    (wire 
        (pts 
            (xy 168.275 149.86) 
            (xy 184.15 149.86)) 
        (stroke 
            (width 0) 
            (type default) 
            (color 0 0 0 0)) 
       ) 
    (wire 
        (pts 
            (xy 153.67 57.785) 
            (xy 153.67 60.325)) 
        (stroke 
            (width 0) 
            (type default) 
            (color 0 0 0 0)) 
       ) 
    (wire 
        (pts 
            (xy 158.75 238.76) 
            (xy 158.75 240.665)) 
        (stroke 
            (width 0) 
            (type default) 
            (color 0 0 0 0)) 
       ) 
    (wire 
        (pts 
            (xy 178.435 210.185) 
            (xy 178.435 215.265)) 
        (stroke 
            (width 0) 
            (type default) 
            (color 0 0 0 0)) 
       ) 
    (wire 
        (pts 
            (xy 219.71 45.72) 
            (xy 230.505 45.72)) 
        (stroke 
            (width 0) 
            (type default) 
            (color 0 0 0 0)) 
       ) 
    (wire 
        (pts 
            (xy 166.37 236.855) 
            (xy 179.07 236.855)) 
        (stroke 
            (width 0) 
            (type default) 
            (color 0 0 0 0)) 
       ) 
    (wire 
        (pts 
            (xy 200.025 60.96) 
            (xy 193.04 60.96)) 
        (stroke 
            (width 0) 
            (type default) 
            (color 0 0 0 0)) 
       ) 
    (wire 
        (pts 
            (xy 193.04 60.96) 
            (xy 193.04 61.595)) 
        (stroke 
            (width 0) 
            (type default) 
            (color 0 0 0 0)) 
       ) 
    (wire 
        (pts 
            (xy 160.655 70.485) 
            (xy 160.655 72.39)) 
        (stroke 
            (width 0) 
            (type default) 
            (color 0 0 0 0)) 
       ) 
    (wire 
        (pts 
            (xy 166.37 255.27) 
            (xy 163.83 255.27)) 
        (stroke 
            (width 0) 
            (type default) 
            (color 0 0 0 0)) 
       ) 
    (polyline 
        (pts 
            (xy 80.01 165.735) 
            (xy 266.065 165.735)) 
        (stroke 
            (width 0) 
            (type default) 
            (color 0 0 0 0)) 
       ) 
    (wire 
        (pts 
            (xy 193.04 62.865) 
            (xy 200.025 62.865)) 
        (stroke 
            (width 0) 
            (type default) 
            (color 0 0 0 0)) 
       ) 
    (wire 
        (pts 
            (xy 176.53 153.67) 
            (xy 177.165 153.67)) 
        (stroke 
            (width 0) 
            (type default) 
            (color 0 0 0 0)) 
       ) 
    (wire 
        (pts 
            (xy 200.025 63.5) 
            (xy 196.215 63.5)) 
        (stroke 
            (width 0) 
            (type default) 
            (color 0 0 0 0)) 
       ) 
    (wire 
        (pts 
            (xy 166.37 255.27) 
            (xy 166.37 258.445)) 
        (stroke 
            (width 0) 
            (type default) 
            (color 0 0 0 0)) 
       ) 
    (wire 
        (pts 
            (xy 235.585 81.28) 
            (xy 235.585 83.185)) 
        (stroke 
            (width 0) 
            (type default) 
            (color 0 0 0 0)) 
       ) 
    (wire 
        (pts 
            (xy 196.215 59.69) 
            (xy 193.04 59.69)) 
        (stroke 
            (width 0) 
            (type default) 
            (color 0 0 0 0)) 
       ) 
    (wire 
        (pts 
            (xy 163.83 212.09) 
            (xy 165.1 212.09)) 
        (stroke 
            (width 0) 
            (type default) 
            (color 0 0 0 0)) 
       ) 
    (wire 
        (pts 
            (xy 184.15 105.41) 
            (xy 165.1 105.41)) 
        (stroke 
            (width 0) 
            (type default) 
            (color 0 0 0 0)) 
       ) 
    (wire 
        (pts 
            (xy 166.37 258.445) 
            (xy 179.07 258.445)) 
        (stroke 
            (width 0) 
            (type default) 
            (color 0 0 0 0)) 
       ) 
    (polyline 
        (pts 
            (xy 177.8 31.75) 
            (xy 177.8 93.345)) 
        (stroke 
            (width 0) 
            (type default) 
            (color 0 0 0 0)) 
       ) 
    (wire 
        (pts 
            (xy 153.67 67.945) 
            (xy 153.67 70.485)) 
        (stroke 
            (width 0) 
            (type default) 
            (color 0 0 0 0)) 
       ) 
    (wire 
        (pts 
            (xy 153.67 60.325) 
            (xy 160.655 60.325)) 
        (stroke 
            (width 0) 
            (type default) 
            (color 0 0 0 0)) 
       ) 
    (wire 
        (pts 
            (xy 125.73 49.53) 
            (xy 125.73 56.515)) 
        (stroke 
            (width 0) 
            (type default) 
            (color 0 0 0 0)) 
       ) 
    (wire 
        (pts 
            (xy 156.845 55.88) 
            (xy 156.845 57.785)) 
        (stroke 
            (width 0) 
            (type default) 
            (color 0 0 0 0)) 
       ) 
    (wire 
        (pts 
            (xy 153.67 65.405) 
            (xy 160.655 65.405)) 
        (stroke 
            (width 0) 
            (type default) 
            (color 0 0 0 0)) 
       ) 
    (wire 
        (pts 
            (xy 165.735 189.23) 
            (xy 165.735 185.42)) 
        (stroke 
            (width 0) 
            (type default) 
            (color 0 0 0 0)) 
       ) 
    (wire 
        (pts 
            (xy 189.23 217.17) 
            (xy 189.23 219.075)) 
        (stroke 
            (width 0) 
            (type default) 
            (color 0 0 0 0)) 
       ) 
    (wire 
        (pts 
            (xy 151.765 50.8) 
            (xy 149.86 50.8)) 
        (stroke 
            (width 0) 
            (type default) 
            (color 0 0 0 0)) 
       ) 
    (wire 
        (pts 
            (xy 200.025 60.325) 
            (xy 200.025 60.96)) 
        (stroke 
            (width 0) 
            (type default) 
            (color 0 0 0 0)) 
       ) 
    (wire 
        (pts 
            (xy 182.88 184.15) 
            (xy 182.88 180.34)) 
        (stroke 
            (width 0) 
            (type default) 
            (color 0 0 0 0)) 
       ) 
    (polyline 
        (pts 
            (xy 80.01 117.475) 
            (xy 266.065 117.475)) 
        (stroke 
            (width 0) 
            (type default) 
            (color 0 0 0 0)) 
       ) 
    (wire 
        (pts 
            (xy 182.88 185.42) 
            (xy 182.88 189.23)) 
        (stroke 
            (width 0) 
            (type default) 
            (color 0 0 0 0)) 
       ) 
    (wire 
        (pts 
            (xy 189.23 175.26) 
            (xy 189.23 173.355)) 
        (stroke 
            (width 0) 
            (type default) 
            (color 0 0 0 0)) 
       ) 
    (wire 
        (pts 
            (xy 166.37 233.68) 
            (xy 163.83 233.68)) 
        (stroke 
            (width 0) 
            (type default) 
            (color 0 0 0 0)) 
       ) 
    (wire 
        (pts 
            (xy 189.23 154.94) 
            (xy 189.23 156.845)) 
        (stroke 
            (width 0) 
            (type default) 
            (color 0 0 0 0)) 
       ) 
    (wire 
        (pts 
            (xy 165.735 184.15) 
            (xy 182.88 184.15)) 
        (stroke 
            (width 0) 
            (type default) 
            (color 0 0 0 0)) 
       ) 
    (polyline 
        (pts 
            (xy 80.645 30.48) 
            (xy 266.7 30.48)) 
        (stroke 
            (width 0) 
            (type default) 
            (color 0 0 0 0)) 
       ) 
    (wire 
        (pts 
            (xy 153.67 62.865) 
            (xy 153.67 65.405)) 
        (stroke 
            (width 0) 
            (type default) 
            (color 0 0 0 0)) 
       ) 
    (polyline 
        (pts 
            (xy 80.01 202.565) 
            (xy 266.065 202.565)) 
        (stroke 
            (width 0) 
            (type default) 
            (color 0 0 0 0)) 
       ) 
    (wire 
        (pts 
            (xy 189.23 260.35) 
            (xy 189.23 267.97)) 
        (stroke 
            (width 0) 
            (type default) 
            (color 0 0 0 0)) 
       ) 
    (wire 
        (pts 
            (xy 156.845 57.785) 
            (xy 153.67 57.785)) 
        (stroke 
            (width 0) 
            (type default) 
            (color 0 0 0 0)) 
       ) 
    (wire 
        (pts 
            (xy 159.385 194.31) 
            (xy 159.385 196.215)) 
        (stroke 
            (width 0) 
            (type default) 
            (color 0 0 0 0)) 
       ) 
    (wire 
        (pts 
            (xy 108.585 54.61) 
            (xy 108.585 56.515)) 
        (stroke 
            (width 0) 
            (type default) 
            (color 0 0 0 0)) 
       ) 
    (wire 
        (pts 
            (xy 160.655 67.945) 
            (xy 153.67 67.945)) 
        (stroke 
            (width 0) 
            (type default) 
            (color 0 0 0 0)) 
       ) 
    (wire 
        (pts 
            (xy 189.23 238.76) 
            (xy 189.23 240.665)) 
        (stroke 
            (width 0) 
            (type default) 
            (color 0 0 0 0)) 
       ) 
    (polyline 
        (pts 
            (xy 266.7 30.48) 
            (xy 266.7 273.05)) 
        (stroke 
            (width 0) 
            (type default) 
            (color 0 0 0 0)) 
       ) 
    (wire 
        (pts 
            (xy 160.02 110.49) 
            (xy 160.02 112.395)) 
        (stroke 
            (width 0) 
            (type default) 
            (color 0 0 0 0)) 
       ) 
    (wire 
        (pts 
            (xy 219.71 44.45) 
            (xy 219.71 45.72)) 
        (stroke 
            (width 0) 
            (type default) 
            (color 0 0 0 0)) 
       ) 
    (wire 
        (pts 
            (xy 196.215 55.88) 
            (xy 196.215 59.69)) 
        (stroke 
            (width 0) 
            (type default) 
            (color 0 0 0 0)) 
       ) 
    (wire 
        (pts 
            (xy 120.65 49.53) 
            (xy 125.73 49.53)) 
        (stroke 
            (width 0) 
            (type default) 
            (color 0 0 0 0)) 
       ) 
    (wire 
        (pts 
            (xy 168.275 126.365) 
            (xy 168.275 131.445)) 
        (stroke 
            (width 0) 
            (type default) 
            (color 0 0 0 0)) 
       ) 
    (polyline 
        (pts 
            (xy 266.7 273.05) 
            (xy 80.645 273.05)) 
        (stroke 
            (width 0) 
            (type default) 
            (color 0 0 0 0)) 
       ) 
    (polyline 
        (pts 
            (xy 213.995 31.75) 
            (xy 213.995 93.98)) 
        (stroke 
            (width 0) 
            (type default) 
            (color 0 0 0 0)) 
       ) 
    (wire 
        (pts 
            (xy 160.02 131.445) 
            (xy 160.02 133.35)) 
        (stroke 
            (width 0) 
            (type default) 
            (color 0 0 0 0)) 
       ) 
    (wire 
        (pts 
            (xy 165.1 212.09) 
            (xy 165.1 219.075)) 
        (stroke 
            (width 0) 
            (type default) 
            (color 0 0 0 0)) 
       ) 
    (wire 
        (pts 
            (xy 168.275 126.365) 
            (xy 165.1 126.365)) 
        (stroke 
            (width 0) 
            (type default) 
            (color 0 0 0 0)) 
       ) 
    (text "3.5-4GHz band-pass inter-digital filter" 
        (at 86.995 213.995 0) 
        (effects 
            (font 
                (size 1.27 1.27) 
                (thickness 0.254) bold) 
            (justify left bottom)) 
       ) 
    (text "with return vias" 
        (at 165.735 233.045 0) 
        (effects 
            (font 
                (size 1.27 1.27)) 
            (justify left bottom)) 
       ) 
    (text "Short stub, 2GHz\n(optional stub short)" 
        (at 86.995 153.035 0) 
        (effects 
            (font 
                (size 1.27 1.27) 
                (thickness 0.254) bold) 
            (justify left bottom)) 
       ) 
    (text "Thight meander 2cm" 
        (at 187.96 36.195 0) 
        (effects 
            (font 
                (size 1.27 1.27) 
                (thickness 0.254) bold) 
            (justify left bottom)) 
       ) 
    (text "Long stub, 1GHz \n(optional stub short)" 
        (at 86.995 130.175 0) 
        (effects 
            (font 
                (size 1.27 1.27) 
                (thickness 0.254) bold) 
            (justify left bottom)) 
       ) 
    (text "4GHz antenna" 
        (at 250.19 47.625 0) 
        (effects 
            (font 
                (size 1.27 1.27) 
                (thickness 0.254) bold) 
            (justify left bottom)) 
       ) 
    (text "Differential pair/ coupler" 
        (at 86.995 184.15 0) 
        (effects 
            (font 
                (size 1.27 1.27) 
                (thickness 0.254) bold) 
            (justify left bottom)) 
       ) 
    (text "Open" 
        (at 255.905 76.835 0) 
        (effects 
            (font 
                (size 1.27 1.27) 
                (thickness 0.254) bold) 
            (justify left bottom)) 
       ) 
    (text "Loose meander 2cm" 
        (at 147.955 36.195 0) 
        (effects 
            (font 
                (size 1.27 1.27) 
                (thickness 0.254) bold) 
            (justify left bottom)) 
       ) 
    (text "Short" 
        (at 83.82 76.835 0) 
        (effects 
            (font 
                (size 1.27 1.27) 
                (thickness 0.254) bold) 
            (justify left bottom)) 
       ) 
    (text "Layer changes" 
        (at 86.995 233.68 0) 
        (effects 
            (font 
                (size 1.27 1.27) 
                (thickness 0.254) bold) 
            (justify left bottom)) 
       ) 
    (text "without vias, optional decoupling on reference change" 
        (at 148.59 252.73 0) 
        (effects 
            (font 
                (size 1.27 1.27)) 
            (justify left bottom)) 
       ) 
    (text "50Ω" 
        (at 85.09 50.165 0) 
        (effects 
            (font 
                (size 1.27 1.27) 
                (thickness 0.254) bold) 
            (justify left bottom)) 
       ) 
    (text "Pass" 
        (at 88.265 107.95 0) 
        (effects 
            (font 
                (size 1.27 1.27) 
                (thickness 0.254) bold) 
            (justify left bottom)) 
       ) 
    (label "DIFF_N" 
        (at 165.735 187.325 0) 
        (effects 
            (font 
                (size 1.27 1.27)) 
            (justify left bottom)) 
       ) 
    (label "DIFF_P" 
        (at 165.735 184.15 0) 
        (effects 
            (font 
                (size 1.27 1.27)) 
            (justify left bottom)) 
       ) 
    (symbol 
        (lib_id "si-simulation-test-board:GND") 
        (at 173.355 219.075 0) 
        (mirror y) 
        (unit 1) 
        (in_bom yes) 
        (on_board yes) 
        (fields_autoplaced) 
        (property "Reference" "#PWR0133" 
            (id 0) 
            (at 164.465 221.615 0) 
            (effects 
                (font 
                    (size 1.27 1.27) 
                    (thickness 0.15)) 
                (justify left bottom) hide)) 
        (property "Value" "GND" 
            (id 1) 
            (at 173.355 223.5118 0) 
            (effects 
                (font 
                    (size 1.27 1.27) 
                    (thickness 0.15)) hide)) 
        (property "Footprint" "" 
            (id 2) 
            (at 164.465 226.695 0) 
            (effects 
                (font 
                    (size 1.27 1.27) 
                    (thickness 0.15)) 
                (justify left bottom) hide)) 
        (property "Datasheet" "" 
            (id 3) 
            (at 164.465 231.775 0) 
            (effects 
                (font 
                    (size 1.27 1.27) 
                    (thickness 0.15)) 
                (justify left bottom) hide)) 
        (property "Author" "Antmicro" 
            (id 4) 
            (at 164.465 226.695 0) 
            (effects 
                (font 
                    (size 1.27 1.27) 
                    (thickness 0.15)) 
                (justify left bottom) hide)) 
        (property "License" "Apache-2.0" 
            (id 5) 
            (at 164.465 229.235 0) 
            (effects 
                (font 
                    (size 1.27 1.27) 
                    (thickness 0.15)) 
                (justify left bottom) hide)) 
        (pin "1" 
           )) 
    (symbol 
        (lib_id "si-simulation-test-board:GND") 
        (at 160.02 133.35 0) 
        (unit 1) 
        (in_bom yes) 
        (on_board yes) 
        (fields_autoplaced) 
        (property "Reference" "#PWR0109" 
            (id 0) 
            (at 168.91 135.89 0) 
            (effects 
                (font 
                    (size 1.27 1.27) 
                    (thickness 0.15)) 
                (justify left bottom) hide)) 
        (property "Value" "GND" 
            (id 1) 
            (at 160.02 137.7868 0) 
            (effects 
                (font 
                    (size 1.27 1.27) 
                    (thickness 0.15)) hide)) 
        (property "Footprint" "" 
            (id 2) 
            (at 168.91 140.97 0) 
            (effects 
                (font 
                    (size 1.27 1.27) 
                    (thickness 0.15)) 
                (justify left bottom) hide)) 
        (property "Datasheet" "" 
            (id 3) 
            (at 168.91 146.05 0) 
            (effects 
                (font 
                    (size 1.27 1.27) 
                    (thickness 0.15)) 
                (justify left bottom) hide)) 
        (property "Author" "Antmicro" 
            (id 4) 
            (at 168.91 140.97 0) 
            (effects 
                (font 
                    (size 1.27 1.27) 
                    (thickness 0.15)) 
                (justify left bottom) hide)) 
        (property "License" "Apache-2.0" 
            (id 5) 
            (at 168.91 143.51 0) 
            (effects 
                (font 
                    (size 1.27 1.27) 
                    (thickness 0.15)) 
                (justify left bottom) hide)) 
        (pin "1" 
           )) 
    (symbol 
        (lib_id "si-simulation-test-board:Antenna") 
        (at 219.71 39.37 0) 
        (unit 1) 
        (in_bom yes) 
        (on_board no) 
        (fields_autoplaced) 
        (property "Reference" "AE1" 
            (id 0) 
            (at 221.742 39.1703 0) 
            (effects 
                (font 
                    (size 1.27 1.27)) 
                (justify left))) 
        (property "Value" "Antenna" 
            (id 1) 
            (at 221.742 41.7072 0) 
            (effects 
                (font 
                    (size 1.27 1.27)) 
                (justify left))) 
        (property "Footprint" "" 
            (id 2) 
            (at 219.71 39.37 0) 
            (effects 
                (font 
                    (size 1.27 1.27)) hide)) 
        (property "Datasheet" "~" 
            (id 3) 
            (at 219.71 39.37 0) 
            (effects 
                (font 
                    (size 1.27 1.27)) hide)) 
        (pin "1" 
           )) 
    (symbol 
        (lib_id "si-simulation-test-board:GND") 
        (at 235.585 52.705 0) 
        (mirror y) 
        (unit 1) 
        (in_bom yes) 
        (on_board yes) 
        (fields_autoplaced) 
        (property "Reference" "#PWR0106" 
            (id 0) 
            (at 226.695 55.245 0) 
            (effects 
                (font 
                    (size 1.27 1.27) 
                    (thickness 0.15)) 
                (justify left bottom) hide)) 
        (property "Value" "GND" 
            (id 1) 
            (at 235.585 57.1418 0) 
            (effects 
                (font 
                    (size 1.27 1.27) 
                    (thickness 0.15)) hide)) 
        (property "Footprint" "" 
            (id 2) 
            (at 226.695 60.325 0) 
            (effects 
                (font 
                    (size 1.27 1.27) 
                    (thickness 0.15)) 
                (justify left bottom) hide)) 
        (property "Datasheet" "" 
            (id 3) 
            (at 226.695 65.405 0) 
            (effects 
                (font 
                    (size 1.27 1.27) 
                    (thickness 0.15)) 
                (justify left bottom) hide)) 
        (property "Author" "Antmicro" 
            (id 4) 
            (at 226.695 60.325 0) 
            (effects 
                (font 
                    (size 1.27 1.27) 
                    (thickness 0.15)) 
                (justify left bottom) hide)) 
        (property "License" "Apache-2.0" 
            (id 5) 
            (at 226.695 62.865 0) 
            (effects 
                (font 
                    (size 1.27 1.27) 
                    (thickness 0.15)) 
                (justify left bottom) hide)) 
        (pin "1" 
           )) 
    (symbol 
        (lib_id "si-simulation-test-board:Conn_SMA_RF2-143-T-17-50-G") 
        (at 184.15 180.34 0) 
        (mirror x) 
        (unit 1) 
        (in_bom yes) 
        (on_board yes) 
        (property "Reference" "J13" 
            (id 0) 
            (at 188.8491 185.8516 0) 
            (effects 
                (font 
                    (size 1.27 1.27) 
                    (thickness 0.15)))) 
        (property "Value" "Conn_SMA_RF2-143-T-17-50-G" 
            (id 1) 
            (at 208.915 180.34 0) 
            (effects 
                (font 
                    (size 1.27 1.27) 
                    (thickness 0.15)) hide)) 
        (property "Footprint" "si-simulation-test-board-footprints:RF_SMA_BoardEdge_RF2-143-T-17-50-G" 
            (id 2) 
            (at 204.47 170.18 0) 
            (effects 
                (font 
                    (size 1.27 1.27) 
                    (thickness 0.15)) 
                (justify left bottom) hide)) 
        (property "Datasheet" "https://www.tme.eu/Document/613028b507cfc72671e78c1d2ad14b1d/RF2-154-T-17-50-G.pdf" 
            (id 3) 
            (at 204.47 167.64 0) 
            (effects 
                (font 
                    (size 1.27 1.27) 
                    (thickness 0.15)) 
                (justify left bottom) hide)) 
        (property "MPN" "RF2-143-T-17-50-G" 
            (id 4) 
            (at 204.47 165.1 0) 
            (effects 
                (font 
                    (size 1.27 1.27) 
                    (thickness 0.15)) 
                (justify left bottom) hide)) 
        (property "Manufacturer" "ADAM TECH" 
            (id 5) 
            (at 204.47 162.56 0) 
            (effects 
                (font 
                    (size 1.27 1.27) 
                    (thickness 0.15)) 
                (justify left bottom) hide)) 
        (property "Author" "Antmicro" 
            (id 6) 
            (at 204.47 160.02 0) 
            (effects 
                (font 
                    (size 1.27 1.27) 
                    (thickness 0.15)) 
                (justify left bottom) hide)) 
        (property "License" "Apache-2.0" 
            (id 7) 
            (at 204.47 157.48 0) 
            (effects 
                (font 
                    (size 1.27 1.27) 
                    (thickness 0.15)) 
                (justify left bottom) hide)) 
        (pin "1" 
           ) 
        (pin "2" 
           )) 
    (symbol 
        (lib_id "si-simulation-test-board:Conn_SMA_RF2-143-T-17-50-G") 
        (at 184.15 212.09 0) 
        (unit 1) 
        (in_bom yes) 
        (on_board yes) 
        (fields_autoplaced) 
        (property "Reference" "J20" 
            (id 0) 
            (at 191.77 211.6161 0) 
            (effects 
                (font 
                    (size 1.27 1.27) 
                    (thickness 0.15)) 
                (justify left))) 
        (property "Value" "Conn_SMA_RF2-143-T-17-50-G" 
            (id 1) 
            (at 191.77 214.1398 0) 
            (effects 
                (font 
                    (size 1.27 1.27) 
                    (thickness 0.15)) 
                (justify left) hide)) 
        (property "Footprint" "si-simulation-test-board-footprints:RF_SMA_BoardEdge_RF2-143-T-17-50-G" 
            (id 2) 
            (at 204.47 222.25 0) 
            (effects 
                (font 
                    (size 1.27 1.27) 
                    (thickness 0.15)) 
                (justify left bottom) hide)) 
        (property "Datasheet" "https://www.tme.eu/Document/613028b507cfc72671e78c1d2ad14b1d/RF2-154-T-17-50-G.pdf" 
            (id 3) 
            (at 204.47 224.79 0) 
            (effects 
                (font 
                    (size 1.27 1.27) 
                    (thickness 0.15)) 
                (justify left bottom) hide)) 
        (property "MPN" "RF2-143-T-17-50-G" 
            (id 4) 
            (at 204.47 227.33 0) 
            (effects 
                (font 
                    (size 1.27 1.27) 
                    (thickness 0.15)) 
                (justify left bottom) hide)) 
        (property "Manufacturer" "ADAM TECH" 
            (id 5) 
            (at 204.47 229.87 0) 
            (effects 
                (font 
                    (size 1.27 1.27) 
                    (thickness 0.15)) 
                (justify left bottom) hide)) 
        (property "Author" "Antmicro" 
            (id 6) 
            (at 204.47 232.41 0) 
            (effects 
                (font 
                    (size 1.27 1.27) 
                    (thickness 0.15)) 
                (justify left bottom) hide)) 
        (property "License" "Apache-2.0" 
            (id 7) 
            (at 204.47 234.95 0) 
            (effects 
                (font 
                    (size 1.27 1.27) 
                    (thickness 0.15)) 
                (justify left bottom) hide)) 
        (pin "1" 
           ) 
        (pin "2" 
           )) 
    (symbol 
        (lib_id "si-simulation-test-board:R_50R_0402") 
        (at 115.57 49.53 0) 
        (unit 1) 
        (in_bom yes) 
        (on_board yes) 
        (fields_autoplaced) 
        (property "Reference" "R2" 
            (id 0) 
            (at 118.11 44.956 0) 
            (effects 
                (font 
                    (size 1.27 1.27) 
                    (thickness 0.15)))) 
        (property "Value" "R_50R_0402" 
            (id 1) 
            (at 135.89 62.23 0) 
            (effects 
                (font 
                    (size 1.27 1.27) 
                    (thickness 0.15)) 
                (justify left bottom) hide)) 
        (property "Footprint" "si-simulation-test-board-footprints:R_0402_1005Metric" 
            (id 2) 
            (at 135.89 64.77 0) 
            (effects 
                (font 
                    (size 1.27 1.27) 
                    (thickness 0.15)) 
                (justify left bottom) hide)) 
        (property "Datasheet" "https://www.bourns.com/docs/product-datasheets/cr.pdf" 
            (id 3) 
            (at 135.89 67.31 0) 
            (effects 
                (font 
                    (size 1.27 1.27) 
                    (thickness 0.15)) 
                (justify left bottom) hide)) 
        (property "MPN" "CR0402-FX-50R0GLF" 
            (id 4) 
            (at 135.89 69.85 0) 
            (effects 
                (font 
                    (size 1.27 1.27) 
                    (thickness 0.15)) 
                (justify left bottom) hide)) 
        (property "Manufacturer" "Bourns" 
            (id 5) 
            (at 135.89 72.39 0) 
            (effects 
                (font 
                    (size 1.27 1.27) 
                    (thickness 0.15)) 
                (justify left bottom) hide)) 
        (property "License" "Apache-2.0" 
            (id 6) 
            (at 135.89 74.93 0) 
            (effects 
                (font 
                    (size 1.27 1.27) 
                    (thickness 0.15)) 
                (justify left bottom) hide)) 
        (property "Author" "Antmicro" 
            (id 7) 
            (at 135.89 77.47 0) 
            (effects 
                (font 
                    (size 1.27 1.27) 
                    (thickness 0.15)) 
                (justify left bottom) hide)) 
        (property "Val" "50R" 
            (id 8) 
            (at 118.11 47.4797 0) 
            (effects 
                (font 
                    (size 1.27 1.27) 
                    (thickness 0.15)))) 
        (property "Tolerance" "1%" 
            (id 9) 
            (at 135.89 59.69 0) 
            (effects 
                (font 
                    (size 1.27 1.27)) 
                (justify left bottom) hide)) 
        (pin "1" 
           ) 
        (pin "2" 
           )) 
    (symbol 
        (lib_id "si-simulation-test-board:Conn_SMA_RF2-143-T-17-50-G") 
        (at 184.15 189.23 0) 
        (unit 1) 
        (in_bom yes) 
        (on_board yes) 
        (fields_autoplaced) 
        (property "Reference" "J14" 
            (id 0) 
            (at 191.77 188.7561 0) 
            (effects 
                (font 
                    (size 1.27 1.27) 
                    (thickness 0.15)) 
                (justify left))) 
        (property "Value" "Conn_SMA_RF2-143-T-17-50-G" 
            (id 1) 
            (at 191.77 191.2798 0) 
            (effects 
                (font 
                    (size 1.27 1.27) 
                    (thickness 0.15)) 
                (justify left) hide)) 
        (property "Footprint" "si-simulation-test-board-footprints:RF_SMA_BoardEdge_RF2-143-T-17-50-G" 
            (id 2) 
            (at 204.47 199.39 0) 
            (effects 
                (font 
                    (size 1.27 1.27) 
                    (thickness 0.15)) 
                (justify left bottom) hide)) 
        (property "Datasheet" "https://www.tme.eu/Document/613028b507cfc72671e78c1d2ad14b1d/RF2-154-T-17-50-G.pdf" 
            (id 3) 
            (at 204.47 201.93 0) 
            (effects 
                (font 
                    (size 1.27 1.27) 
                    (thickness 0.15)) 
                (justify left bottom) hide)) 
        (property "MPN" "RF2-143-T-17-50-G" 
            (id 4) 
            (at 204.47 204.47 0) 
            (effects 
                (font 
                    (size 1.27 1.27) 
                    (thickness 0.15)) 
                (justify left bottom) hide)) 
        (property "Manufacturer" "ADAM TECH" 
            (id 5) 
            (at 204.47 207.01 0) 
            (effects 
                (font 
                    (size 1.27 1.27) 
                    (thickness 0.15)) 
                (justify left bottom) hide)) 
        (property "Author" "Antmicro" 
            (id 6) 
            (at 204.47 209.55 0) 
            (effects 
                (font 
                    (size 1.27 1.27) 
                    (thickness 0.15)) 
                (justify left bottom) hide)) 
        (property "License" "Apache-2.0" 
            (id 7) 
            (at 204.47 212.09 0) 
            (effects 
                (font 
                    (size 1.27 1.27) 
                    (thickness 0.15)) 
                (justify left bottom) hide)) 
        (pin "1" 
           ) 
        (pin "2" 
           )) 
    (symbol 
        (lib_id "si-simulation-test-board:GND") 
        (at 159.385 196.215 0) 
        (unit 1) 
        (in_bom yes) 
        (on_board yes) 
        (fields_autoplaced) 
        (property "Reference" "#PWR0116" 
            (id 0) 
            (at 168.275 198.755 0) 
            (effects 
                (font 
                    (size 1.27 1.27) 
                    (thickness 0.15)) 
                (justify left bottom) hide)) 
        (property "Value" "GND" 
            (id 1) 
            (at 159.385 200.6518 0) 
            (effects 
                (font 
                    (size 1.27 1.27) 
                    (thickness 0.15)) hide)) 
        (property "Footprint" "" 
            (id 2) 
            (at 168.275 203.835 0) 
            (effects 
                (font 
                    (size 1.27 1.27) 
                    (thickness 0.15)) 
                (justify left bottom) hide)) 
        (property "Datasheet" "" 
            (id 3) 
            (at 168.275 208.915 0) 
            (effects 
                (font 
                    (size 1.27 1.27) 
                    (thickness 0.15)) 
                (justify left bottom) hide)) 
        (property "Author" "Antmicro" 
            (id 4) 
            (at 168.275 203.835 0) 
            (effects 
                (font 
                    (size 1.27 1.27) 
                    (thickness 0.15)) 
                (justify left bottom) hide)) 
        (property "License" "Apache-2.0" 
            (id 5) 
            (at 168.275 206.375 0) 
            (effects 
                (font 
                    (size 1.27 1.27) 
                    (thickness 0.15)) 
                (justify left bottom) hide)) 
        (pin "1" 
           )) 
    (symbol 
        (lib_id "si-simulation-test-board:GND") 
        (at 189.23 156.845 0) 
        (unit 1) 
        (in_bom yes) 
        (on_board yes) 
        (fields_autoplaced) 
        (property "Reference" "#PWR0113" 
            (id 0) 
            (at 198.12 159.385 0) 
            (effects 
                (font 
                    (size 1.27 1.27) 
                    (thickness 0.15)) 
                (justify left bottom) hide)) 
        (property "Value" "GND" 
            (id 1) 
            (at 189.23 161.2818 0) 
            (effects 
                (font 
                    (size 1.27 1.27) 
                    (thickness 0.15)) hide)) 
        (property "Footprint" "" 
            (id 2) 
            (at 198.12 164.465 0) 
            (effects 
                (font 
                    (size 1.27 1.27) 
                    (thickness 0.15)) 
                (justify left bottom) hide)) 
        (property "Datasheet" "" 
            (id 3) 
            (at 198.12 169.545 0) 
            (effects 
                (font 
                    (size 1.27 1.27) 
                    (thickness 0.15)) 
                (justify left bottom) hide)) 
        (property "Author" "Antmicro" 
            (id 4) 
            (at 198.12 164.465 0) 
            (effects 
                (font 
                    (size 1.27 1.27) 
                    (thickness 0.15)) 
                (justify left bottom) hide)) 
        (property "License" "Apache-2.0" 
            (id 5) 
            (at 198.12 167.005 0) 
            (effects 
                (font 
                    (size 1.27 1.27) 
                    (thickness 0.15)) 
                (justify left bottom) hide)) 
        (pin "1" 
           )) 
    (symbol 
        (lib_id "si-simulation-test-board:GND") 
        (at 189.23 112.395 0) 
        (unit 1) 
        (in_bom yes) 
        (on_board yes) 
        (fields_autoplaced) 
        (property "Reference" "#PWR0102" 
            (id 0) 
            (at 198.12 114.935 0) 
            (effects 
                (font 
                    (size 1.27 1.27) 
                    (thickness 0.15)) 
                (justify left bottom) hide)) 
        (property "Value" "GND" 
            (id 1) 
            (at 189.23 116.8318 0) 
            (effects 
                (font 
                    (size 1.27 1.27) 
                    (thickness 0.15)) hide)) 
        (property "Footprint" "" 
            (id 2) 
            (at 198.12 120.015 0) 
            (effects 
                (font 
                    (size 1.27 1.27) 
                    (thickness 0.15)) 
                (justify left bottom) hide)) 
        (property "Datasheet" "" 
            (id 3) 
            (at 198.12 125.095 0) 
            (effects 
                (font 
                    (size 1.27 1.27) 
                    (thickness 0.15)) 
                (justify left bottom) hide)) 
        (property "Author" "Antmicro" 
            (id 4) 
            (at 198.12 120.015 0) 
            (effects 
                (font 
                    (size 1.27 1.27) 
                    (thickness 0.15)) 
                (justify left bottom) hide)) 
        (property "License" "Apache-2.0" 
            (id 5) 
            (at 198.12 122.555 0) 
            (effects 
                (font 
                    (size 1.27 1.27) 
                    (thickness 0.15)) 
                (justify left bottom) hide)) 
        (pin "1" 
           )) 
    (symbol 
        (lib_id "si-simulation-test-board:Conn_SMA_RF2-143-T-17-50-G") 
        (at 163.83 255.27 0) 
        (mirror y) 
        (unit 1) 
        (in_bom yes) 
        (on_board yes) 
        (fields_autoplaced) 
        (property "Reference" "J16" 
            (id 0) 
            (at 156.2099 256.0579 0) 
            (effects 
                (font 
                    (size 1.27 1.27) 
                    (thickness 0.15)) 
                (justify left))) 
        (property "Value" "Conn_SMA_RF2-143-T-17-50-G" 
            (id 1) 
            (at 139.065 255.27 0) 
            (effects 
                (font 
                    (size 1.27 1.27) 
                    (thickness 0.15)) hide)) 
        (property "Footprint" "si-simulation-test-board-footprints:RF_SMA_BoardEdge_RF2-143-T-17-50-G" 
            (id 2) 
            (at 143.51 265.43 0) 
            (effects 
                (font 
                    (size 1.27 1.27) 
                    (thickness 0.15)) 
                (justify left bottom) hide)) 
        (property "Datasheet" "https://www.tme.eu/Document/613028b507cfc72671e78c1d2ad14b1d/RF2-154-T-17-50-G.pdf" 
            (id 3) 
            (at 143.51 267.97 0) 
            (effects 
                (font 
                    (size 1.27 1.27) 
                    (thickness 0.15)) 
                (justify left bottom) hide)) 
        (property "MPN" "RF2-143-T-17-50-G" 
            (id 4) 
            (at 143.51 270.51 0) 
            (effects 
                (font 
                    (size 1.27 1.27) 
                    (thickness 0.15)) 
                (justify left bottom) hide)) 
        (property "Manufacturer" "ADAM TECH" 
            (id 5) 
            (at 143.51 273.05 0) 
            (effects 
                (font 
                    (size 1.27 1.27) 
                    (thickness 0.15)) 
                (justify left bottom) hide)) 
        (property "Author" "Antmicro" 
            (id 6) 
            (at 143.51 275.59 0) 
            (effects 
                (font 
                    (size 1.27 1.27) 
                    (thickness 0.15)) 
                (justify left bottom) hide)) 
        (property "License" "Apache-2.0" 
            (id 7) 
            (at 143.51 278.13 0) 
            (effects 
                (font 
                    (size 1.27 1.27) 
                    (thickness 0.15)) 
                (justify left bottom) hide)) 
        (pin "1" 
           ) 
        (pin "2" 
           )) 
    (symbol 
        (lib_id "si-simulation-test-board:Conn_SMA_RF2-143-T-17-50-G") 
        (at 184.15 233.68 0) 
        (unit 1) 
        (in_bom yes) 
        (on_board yes) 
        (fields_autoplaced) 
        (property "Reference" "J17" 
            (id 0) 
            (at 191.77 233.2061 0) 
            (effects 
                (font 
                    (size 1.27 1.27) 
                    (thickness 0.15)) 
                (justify left))) 
        (property "Value" "Conn_SMA_RF2-143-T-17-50-G" 
            (id 1) 
            (at 191.77 235.7298 0) 
            (effects 
                (font 
                    (size 1.27 1.27) 
                    (thickness 0.15)) 
                (justify left) hide)) 
        (property "Footprint" "si-simulation-test-board-footprints:RF_SMA_BoardEdge_RF2-143-T-17-50-G" 
            (id 2) 
            (at 204.47 243.84 0) 
            (effects 
                (font 
                    (size 1.27 1.27) 
                    (thickness 0.15)) 
                (justify left bottom) hide)) 
        (property "Datasheet" "https://www.tme.eu/Document/613028b507cfc72671e78c1d2ad14b1d/RF2-154-T-17-50-G.pdf" 
            (id 3) 
            (at 204.47 246.38 0) 
            (effects 
                (font 
                    (size 1.27 1.27) 
                    (thickness 0.15)) 
                (justify left bottom) hide)) 
        (property "MPN" "RF2-143-T-17-50-G" 
            (id 4) 
            (at 204.47 248.92 0) 
            (effects 
                (font 
                    (size 1.27 1.27) 
                    (thickness 0.15)) 
                (justify left bottom) hide)) 
        (property "Manufacturer" "ADAM TECH" 
            (id 5) 
            (at 204.47 251.46 0) 
            (effects 
                (font 
                    (size 1.27 1.27) 
                    (thickness 0.15)) 
                (justify left bottom) hide)) 
        (property "Author" "Antmicro" 
            (id 6) 
            (at 204.47 254 0) 
            (effects 
                (font 
                    (size 1.27 1.27) 
                    (thickness 0.15)) 
                (justify left bottom) hide)) 
        (property "License" "Apache-2.0" 
            (id 7) 
            (at 204.47 256.54 0) 
            (effects 
                (font 
                    (size 1.27 1.27) 
                    (thickness 0.15)) 
                (justify left bottom) hide)) 
        (pin "1" 
           ) 
        (pin "2" 
           )) 
    (symbol 
        (lib_id "si-simulation-test-board:GND") 
        (at 183.515 131.445 90) 
        (unit 1) 
        (in_bom yes) 
        (on_board yes) 
        (fields_autoplaced) 
        (property "Reference" "#PWR0114" 
            (id 0) 
            (at 186.055 122.555 0) 
            (effects 
                (font 
                    (size 1.27 1.27) 
                    (thickness 0.15)) 
                (justify left bottom) hide)) 
        (property "Value" "GND" 
            (id 1) 
            (at 187.9518 131.445 0) 
            (effects 
                (font 
                    (size 1.27 1.27) 
                    (thickness 0.15)) hide)) 
        (property "Footprint" "" 
            (id 2) 
            (at 191.135 122.555 0) 
            (effects 
                (font 
                    (size 1.27 1.27) 
                    (thickness 0.15)) 
                (justify left bottom) hide)) 
        (property "Datasheet" "" 
            (id 3) 
            (at 196.215 122.555 0) 
            (effects 
                (font 
                    (size 1.27 1.27) 
                    (thickness 0.15)) 
                (justify left bottom) hide)) 
        (property "Author" "Antmicro" 
            (id 4) 
            (at 191.135 122.555 0) 
            (effects 
                (font 
                    (size 1.27 1.27) 
                    (thickness 0.15)) 
                (justify left bottom) hide)) 
        (property "License" "Apache-2.0" 
            (id 5) 
            (at 193.675 122.555 0) 
            (effects 
                (font 
                    (size 1.27 1.27) 
                    (thickness 0.15)) 
                (justify left bottom) hide)) 
        (pin "1" 
           )) 
    (symbol 
        (lib_id "si-simulation-test-board:GND") 
        (at 165.1 219.075 0) 
        (unit 1) 
        (in_bom yes) 
        (on_board yes) 
        (fields_autoplaced) 
        (property "Reference" "#PWR0128" 
            (id 0) 
            (at 173.99 221.615 0) 
            (effects 
                (font 
                    (size 1.27 1.27) 
                    (thickness 0.15)) 
                (justify left bottom) hide)) 
        (property "Value" "GND" 
            (id 1) 
            (at 165.1 223.5118 0) 
            (effects 
                (font 
                    (size 1.27 1.27) 
                    (thickness 0.15)) hide)) 
        (property "Footprint" "" 
            (id 2) 
            (at 173.99 226.695 0) 
            (effects 
                (font 
                    (size 1.27 1.27) 
                    (thickness 0.15)) 
                (justify left bottom) hide)) 
        (property "Datasheet" "" 
            (id 3) 
            (at 173.99 231.775 0) 
            (effects 
                (font 
                    (size 1.27 1.27) 
                    (thickness 0.15)) 
                (justify left bottom) hide)) 
        (property "Author" "Antmicro" 
            (id 4) 
            (at 173.99 226.695 0) 
            (effects 
                (font 
                    (size 1.27 1.27) 
                    (thickness 0.15)) 
                (justify left bottom) hide)) 
        (property "License" "Apache-2.0" 
            (id 5) 
            (at 173.99 229.235 0) 
            (effects 
                (font 
                    (size 1.27 1.27) 
                    (thickness 0.15)) 
                (justify left bottom) hide)) 
        (pin "1" 
           )) 
    (symbol 
        (lib_id "si-simulation-test-board:GND") 
        (at 125.73 56.515 0) 
        (unit 1) 
        (in_bom yes) 
        (on_board yes) 
        (fields_autoplaced) 
        (property "Reference" "#PWR0110" 
            (id 0) 
            (at 134.62 59.055 0) 
            (effects 
                (font 
                    (size 1.27 1.27) 
                    (thickness 0.15)) 
                (justify left bottom) hide)) 
        (property "Value" "GND" 
            (id 1) 
            (at 125.73 60.9518 0) 
            (effects 
                (font 
                    (size 1.27 1.27) 
                    (thickness 0.15)) hide)) 
        (property "Footprint" "" 
            (id 2) 
            (at 134.62 64.135 0) 
            (effects 
                (font 
                    (size 1.27 1.27) 
                    (thickness 0.15)) 
                (justify left bottom) hide)) 
        (property "Datasheet" "" 
            (id 3) 
            (at 134.62 69.215 0) 
            (effects 
                (font 
                    (size 1.27 1.27) 
                    (thickness 0.15)) 
                (justify left bottom) hide)) 
        (property "Author" "Antmicro" 
            (id 4) 
            (at 134.62 64.135 0) 
            (effects 
                (font 
                    (size 1.27 1.27) 
                    (thickness 0.15)) 
                (justify left bottom) hide)) 
        (property "License" "Apache-2.0" 
            (id 5) 
            (at 134.62 66.675 0) 
            (effects 
                (font 
                    (size 1.27 1.27) 
                    (thickness 0.15)) 
                (justify left bottom) hide)) 
        (pin "1" 
           )) 
    (symbol 
        (lib_id "si-simulation-test-board:GND") 
        (at 167.005 262.89 180) 
        (unit 1) 
        (in_bom yes) 
        (on_board yes) 
        (fields_autoplaced) 
        (property "Reference" "#PWR0130" 
            (id 0) 
            (at 158.115 260.35 0) 
            (effects 
                (font 
                    (size 1.27 1.27) 
                    (thickness 0.15)) 
                (justify left bottom) hide)) 
        (property "Value" "GND" 
            (id 1) 
            (at 168.91 262.0512 0) 
            (effects 
                (font 
                    (size 1.27 1.27) 
                    (thickness 0.15)) 
                (justify right) hide)) 
        (property "Footprint" "" 
            (id 2) 
            (at 158.115 255.27 0) 
            (effects 
                (font 
                    (size 1.27 1.27) 
                    (thickness 0.15)) 
                (justify left bottom) hide)) 
        (property "Datasheet" "" 
            (id 3) 
            (at 158.115 250.19 0) 
            (effects 
                (font 
                    (size 1.27 1.27) 
                    (thickness 0.15)) 
                (justify left bottom) hide)) 
        (property "Author" "Antmicro" 
            (id 4) 
            (at 158.115 255.27 0) 
            (effects 
                (font 
                    (size 1.27 1.27) 
                    (thickness 0.15)) 
                (justify left bottom) hide)) 
        (property "License" "Apache-2.0" 
            (id 5) 
            (at 158.115 252.73 0) 
            (effects 
                (font 
                    (size 1.27 1.27) 
                    (thickness 0.15)) 
                (justify left bottom) hide)) 
        (pin "1" 
           )) 
    (symbol 
        (lib_id "si-simulation-test-board:GND") 
        (at 158.75 240.665 0) 
        (unit 1) 
        (in_bom yes) 
        (on_board yes) 
        (fields_autoplaced) 
        (property "Reference" "#PWR0123" 
            (id 0) 
            (at 167.64 243.205 0) 
            (effects 
                (font 
                    (size 1.27 1.27) 
                    (thickness 0.15)) 
                (justify left bottom) hide)) 
        (property "Value" "GND" 
            (id 1) 
            (at 158.75 245.1018 0) 
            (effects 
                (font 
                    (size 1.27 1.27) 
                    (thickness 0.15)) hide)) 
        (property "Footprint" "" 
            (id 2) 
            (at 167.64 248.285 0) 
            (effects 
                (font 
                    (size 1.27 1.27) 
                    (thickness 0.15)) 
                (justify left bottom) hide)) 
        (property "Datasheet" "" 
            (id 3) 
            (at 167.64 253.365 0) 
            (effects 
                (font 
                    (size 1.27 1.27) 
                    (thickness 0.15)) 
                (justify left bottom) hide)) 
        (property "Author" "Antmicro" 
            (id 4) 
            (at 167.64 248.285 0) 
            (effects 
                (font 
                    (size 1.27 1.27) 
                    (thickness 0.15)) 
                (justify left bottom) hide)) 
        (property "License" "Apache-2.0" 
            (id 5) 
            (at 167.64 250.825 0) 
            (effects 
                (font 
                    (size 1.27 1.27) 
                    (thickness 0.15)) 
                (justify left bottom) hide)) 
        (pin "1" 
           )) 
    (symbol 
        (lib_id "si-simulation-test-board:GND") 
        (at 159.385 156.845 0) 
        (unit 1) 
        (in_bom yes) 
        (on_board yes) 
        (fields_autoplaced) 
        (property "Reference" "#PWR0112" 
            (id 0) 
            (at 168.275 159.385 0) 
            (effects 
                (font 
                    (size 1.27 1.27) 
                    (thickness 0.15)) 
                (justify left bottom) hide)) 
        (property "Value" "GND" 
            (id 1) 
            (at 159.385 161.2818 0) 
            (effects 
                (font 
                    (size 1.27 1.27) 
                    (thickness 0.15)) hide)) 
        (property "Footprint" "" 
            (id 2) 
            (at 168.275 164.465 0) 
            (effects 
                (font 
                    (size 1.27 1.27) 
                    (thickness 0.15)) 
                (justify left bottom) hide)) 
        (property "Datasheet" "" 
            (id 3) 
            (at 168.275 169.545 0) 
            (effects 
                (font 
                    (size 1.27 1.27) 
                    (thickness 0.15)) 
                (justify left bottom) hide)) 
        (property "Author" "Antmicro" 
            (id 4) 
            (at 168.275 164.465 0) 
            (effects 
                (font 
                    (size 1.27 1.27) 
                    (thickness 0.15)) 
                (justify left bottom) hide)) 
        (property "License" "Apache-2.0" 
            (id 5) 
            (at 168.275 167.005 0) 
            (effects 
                (font 
                    (size 1.27 1.27) 
                    (thickness 0.15)) 
                (justify left bottom) hide)) 
        (pin "1" 
           )) 
    (symbol 
        (lib_id "si-simulation-test-board:GND") 
        (at 108.585 56.515 0) 
        (unit 1) 
        (in_bom yes) 
        (on_board yes) 
        (fields_autoplaced) 
        (property "Reference" "#PWR0108" 
            (id 0) 
            (at 117.475 59.055 0) 
            (effects 
                (font 
                    (size 1.27 1.27) 
                    (thickness 0.15)) 
                (justify left bottom) hide)) 
        (property "Value" "GND" 
            (id 1) 
            (at 108.585 60.9518 0) 
            (effects 
                (font 
                    (size 1.27 1.27) 
                    (thickness 0.15)) hide)) 
        (property "Footprint" "" 
            (id 2) 
            (at 117.475 64.135 0) 
            (effects 
                (font 
                    (size 1.27 1.27) 
                    (thickness 0.15)) 
                (justify left bottom) hide)) 
        (property "Datasheet" "" 
            (id 3) 
            (at 117.475 69.215 0) 
            (effects 
                (font 
                    (size 1.27 1.27) 
                    (thickness 0.15)) 
                (justify left bottom) hide)) 
        (property "Author" "Antmicro" 
            (id 4) 
            (at 117.475 64.135 0) 
            (effects 
                (font 
                    (size 1.27 1.27) 
                    (thickness 0.15)) 
                (justify left bottom) hide)) 
        (property "License" "Apache-2.0" 
            (id 5) 
            (at 117.475 66.675 0) 
            (effects 
                (font 
                    (size 1.27 1.27) 
                    (thickness 0.15)) 
                (justify left bottom) hide)) 
        (pin "1" 
           )) 
    (symbol 
        (lib_id "si-simulation-test-board:GND") 
        (at 111.125 82.55 0) 
        (unit 1) 
        (in_bom yes) 
        (on_board yes) 
        (fields_autoplaced) 
        (property "Reference" "#PWR0104" 
            (id 0) 
            (at 120.015 85.09 0) 
            (effects 
                (font 
                    (size 1.27 1.27) 
                    (thickness 0.15)) 
                (justify left bottom) hide)) 
        (property "Value" "GND" 
            (id 1) 
            (at 111.125 86.9868 0) 
            (effects 
                (font 
                    (size 1.27 1.27) 
                    (thickness 0.15)) hide)) 
        (property "Footprint" "" 
            (id 2) 
            (at 120.015 90.17 0) 
            (effects 
                (font 
                    (size 1.27 1.27) 
                    (thickness 0.15)) 
                (justify left bottom) hide)) 
        (property "Datasheet" "" 
            (id 3) 
            (at 120.015 95.25 0) 
            (effects 
                (font 
                    (size 1.27 1.27) 
                    (thickness 0.15)) 
                (justify left bottom) hide)) 
        (property "Author" "Antmicro" 
            (id 4) 
            (at 120.015 90.17 0) 
            (effects 
                (font 
                    (size 1.27 1.27) 
                    (thickness 0.15)) 
                (justify left bottom) hide)) 
        (property "License" "Apache-2.0" 
            (id 5) 
            (at 120.015 92.71 0) 
            (effects 
                (font 
                    (size 1.27 1.27) 
                    (thickness 0.15)) 
                (justify left bottom) hide)) 
        (pin "1" 
           )) 
    (symbol 
        (lib_id "si-simulation-test-board:Conn_SMA_RF2-143-T-17-50-G") 
        (at 113.665 49.53 0) 
        (mirror y) 
        (unit 1) 
        (in_bom yes) 
        (on_board yes) 
        (property "Reference" "J6" 
            (id 0) 
            (at 108.9659 44.0184 0) 
            (effects 
                (font 
                    (size 1.27 1.27) 
                    (thickness 0.15)))) 
        (property "Value" "Conn_SMA_RF2-143-T-17-50-G" 
            (id 1) 
            (at 88.9 49.53 0) 
            (effects 
                (font 
                    (size 1.27 1.27) 
                    (thickness 0.15)) hide)) 
        (property "Footprint" "si-simulation-test-board-footprints:RF_SMA_BoardEdge_RF2-143-T-17-50-G" 
            (id 2) 
            (at 93.345 59.69 0) 
            (effects 
                (font 
                    (size 1.27 1.27) 
                    (thickness 0.15)) 
                (justify left bottom) hide)) 
        (property "Datasheet" "https://www.tme.eu/Document/613028b507cfc72671e78c1d2ad14b1d/RF2-154-T-17-50-G.pdf" 
            (id 3) 
            (at 93.345 62.23 0) 
            (effects 
                (font 
                    (size 1.27 1.27) 
                    (thickness 0.15)) 
                (justify left bottom) hide)) 
        (property "MPN" "RF2-143-T-17-50-G" 
            (id 4) 
            (at 93.345 64.77 0) 
            (effects 
                (font 
                    (size 1.27 1.27) 
                    (thickness 0.15)) 
                (justify left bottom) hide)) 
        (property "Manufacturer" "ADAM TECH" 
            (id 5) 
            (at 93.345 67.31 0) 
            (effects 
                (font 
                    (size 1.27 1.27) 
                    (thickness 0.15)) 
                (justify left bottom) hide)) 
        (property "Author" "Antmicro" 
            (id 6) 
            (at 93.345 69.85 0) 
            (effects 
                (font 
                    (size 1.27 1.27) 
                    (thickness 0.15)) 
                (justify left bottom) hide)) 
        (property "License" "Apache-2.0" 
            (id 7) 
            (at 93.345 72.39 0) 
            (effects 
                (font 
                    (size 1.27 1.27) 
                    (thickness 0.15)) 
                (justify left bottom) hide)) 
        (pin "1" 
           ) 
        (pin "2" 
           )) 
    (symbol 
        (lib_id "si-simulation-test-board:Conn_SMA_RF2-143-T-17-50-G") 
        (at 165.1 126.365 0) 
        (mirror y) 
        (unit 1) 
        (in_bom yes) 
        (on_board yes) 
        (property "Reference" "J7" 
            (id 0) 
            (at 160.4009 120.8534 0) 
            (effects 
                (font 
                    (size 1.27 1.27) 
                    (thickness 0.15)))) 
        (property "Value" "Conn_SMA_RF2-143-T-17-50-G" 
            (id 1) 
            (at 140.335 126.365 0) 
            (effects 
                (font 
                    (size 1.27 1.27) 
                    (thickness 0.15)) hide)) 
        (property "Footprint" "si-simulation-test-board-footprints:RF_SMA_BoardEdge_RF2-143-T-17-50-G" 
            (id 2) 
            (at 144.78 136.525 0) 
            (effects 
                (font 
                    (size 1.27 1.27) 
                    (thickness 0.15)) 
                (justify left bottom) hide)) 
        (property "Datasheet" "https://www.tme.eu/Document/613028b507cfc72671e78c1d2ad14b1d/RF2-154-T-17-50-G.pdf" 
            (id 3) 
            (at 144.78 139.065 0) 
            (effects 
                (font 
                    (size 1.27 1.27) 
                    (thickness 0.15)) 
                (justify left bottom) hide)) 
        (property "MPN" "RF2-143-T-17-50-G" 
            (id 4) 
            (at 144.78 141.605 0) 
            (effects 
                (font 
                    (size 1.27 1.27) 
                    (thickness 0.15)) 
                (justify left bottom) hide)) 
        (property "Manufacturer" "ADAM TECH" 
            (id 5) 
            (at 144.78 144.145 0) 
            (effects 
                (font 
                    (size 1.27 1.27) 
                    (thickness 0.15)) 
                (justify left bottom) hide)) 
        (property "Author" "Antmicro" 
            (id 6) 
            (at 144.78 146.685 0) 
            (effects 
                (font 
                    (size 1.27 1.27) 
                    (thickness 0.15)) 
                (justify left bottom) hide)) 
        (property "License" "Apache-2.0" 
            (id 7) 
            (at 144.78 149.225 0) 
            (effects 
                (font 
                    (size 1.27 1.27) 
                    (thickness 0.15)) 
                (justify left bottom) hide)) 
        (pin "1" 
           ) 
        (pin "2" 
           )) 
    (symbol 
        (lib_id "si-simulation-test-board:GND") 
        (at 159.385 173.355 180) 
        (unit 1) 
        (in_bom yes) 
        (on_board yes) 
        (fields_autoplaced) 
        (property "Reference" "#PWR0117" 
            (id 0) 
            (at 150.495 170.815 0) 
            (effects 
                (font 
                    (size 1.27 1.27) 
                    (thickness 0.15)) 
                (justify left bottom) hide)) 
        (property "Value" "GND" 
            (id 1) 
            (at 159.385 168.9182 0) 
            (effects 
                (font 
                    (size 1.27 1.27) 
                    (thickness 0.15)) hide)) 
        (property "Footprint" "" 
            (id 2) 
            (at 150.495 165.735 0) 
            (effects 
                (font 
                    (size 1.27 1.27) 
                    (thickness 0.15)) 
                (justify left bottom) hide)) 
        (property "Datasheet" "" 
            (id 3) 
            (at 150.495 160.655 0) 
            (effects 
                (font 
                    (size 1.27 1.27) 
                    (thickness 0.15)) 
                (justify left bottom) hide)) 
        (property "Author" "Antmicro" 
            (id 4) 
            (at 150.495 165.735 0) 
            (effects 
                (font 
                    (size 1.27 1.27) 
                    (thickness 0.15)) 
                (justify left bottom) hide)) 
        (property "License" "Apache-2.0" 
            (id 5) 
            (at 150.495 163.195 0) 
            (effects 
                (font 
                    (size 1.27 1.27) 
                    (thickness 0.15)) 
                (justify left bottom) hide)) 
        (pin "1" 
           )) 
    (symbol 
        (lib_id "si-simulation-test-board:Conn_SMA_RF2-143-T-17-50-G") 
        (at 184.15 105.41 0) 
        (unit 1) 
        (in_bom yes) 
        (on_board yes) 
        (fields_autoplaced) 
        (property "Reference" "J2" 
            (id 0) 
            (at 191.77 104.9361 0) 
            (effects 
                (font 
                    (size 1.27 1.27) 
                    (thickness 0.15)) 
                (justify left))) 
        (property "Value" "Conn_SMA_RF2-143-T-17-50-G" 
            (id 1) 
            (at 191.77 107.4598 0) 
            (effects 
                (font 
                    (size 1.27 1.27) 
                    (thickness 0.15)) 
                (justify left) hide)) 
        (property "Footprint" "si-simulation-test-board-footprints:RF_SMA_BoardEdge_RF2-143-T-17-50-G" 
            (id 2) 
            (at 204.47 115.57 0) 
            (effects 
                (font 
                    (size 1.27 1.27) 
                    (thickness 0.15)) 
                (justify left bottom) hide)) 
        (property "Datasheet" "https://www.tme.eu/Document/613028b507cfc72671e78c1d2ad14b1d/RF2-154-T-17-50-G.pdf" 
            (id 3) 
            (at 204.47 118.11 0) 
            (effects 
                (font 
                    (size 1.27 1.27) 
                    (thickness 0.15)) 
                (justify left bottom) hide)) 
        (property "MPN" "RF2-143-T-17-50-G" 
            (id 4) 
            (at 204.47 120.65 0) 
            (effects 
                (font 
                    (size 1.27 1.27) 
                    (thickness 0.15)) 
                (justify left bottom) hide)) 
        (property "Manufacturer" "ADAM TECH" 
            (id 5) 
            (at 204.47 123.19 0) 
            (effects 
                (font 
                    (size 1.27 1.27) 
                    (thickness 0.15)) 
                (justify left bottom) hide)) 
        (property "Author" "Antmicro" 
            (id 6) 
            (at 204.47 125.73 0) 
            (effects 
                (font 
                    (size 1.27 1.27) 
                    (thickness 0.15)) 
                (justify left bottom) hide)) 
        (property "License" "Apache-2.0" 
            (id 7) 
            (at 204.47 128.27 0) 
            (effects 
                (font 
                    (size 1.27 1.27) 
                    (thickness 0.15)) 
                (justify left bottom) hide)) 
        (pin "1" 
           ) 
        (pin "2" 
           )) 
    (symbol 
        (lib_id "si-simulation-test-board:Conn_SMA_RF2-143-T-17-50-G") 
        (at 230.505 76.2 0) 
        (unit 1) 
        (in_bom yes) 
        (on_board yes) 
        (property "Reference" "J3" 
            (id 0) 
            (at 235.2041 70.6884 0) 
            (effects 
                (font 
                    (size 1.27 1.27) 
                    (thickness 0.15)))) 
        (property "Value" "Conn_SMA_RF2-143-T-17-50-G" 
            (id 1) 
            (at 255.27 76.2 0) 
            (effects 
                (font 
                    (size 1.27 1.27) 
                    (thickness 0.15)) hide)) 
        (property "Footprint" "si-simulation-test-board-footprints:RF_SMA_BoardEdge_RF2-143-T-17-50-G" 
            (id 2) 
            (at 250.825 86.36 0) 
            (effects 
                (font 
                    (size 1.27 1.27) 
                    (thickness 0.15)) 
                (justify left bottom) hide)) 
        (property "Datasheet" "https://www.tme.eu/Document/613028b507cfc72671e78c1d2ad14b1d/RF2-154-T-17-50-G.pdf" 
            (id 3) 
            (at 250.825 88.9 0) 
            (effects 
                (font 
                    (size 1.27 1.27) 
                    (thickness 0.15)) 
                (justify left bottom) hide)) 
        (property "MPN" "RF2-143-T-17-50-G" 
            (id 4) 
            (at 250.825 91.44 0) 
            (effects 
                (font 
                    (size 1.27 1.27) 
                    (thickness 0.15)) 
                (justify left bottom) hide)) 
        (property "Manufacturer" "ADAM TECH" 
            (id 5) 
            (at 250.825 93.98 0) 
            (effects 
                (font 
                    (size 1.27 1.27) 
                    (thickness 0.15)) 
                (justify left bottom) hide)) 
        (property "Author" "Antmicro" 
            (id 6) 
            (at 250.825 96.52 0) 
            (effects 
                (font 
                    (size 1.27 1.27) 
                    (thickness 0.15)) 
                (justify left bottom) hide)) 
        (property "License" "Apache-2.0" 
            (id 7) 
            (at 250.825 99.06 0) 
            (effects 
                (font 
                    (size 1.27 1.27) 
                    (thickness 0.15)) 
                (justify left bottom) hide)) 
        (pin "1" 
           ) 
        (pin "2" 
           )) 
    (symbol 
        (lib_id "si-simulation-test-board:GND") 
        (at 160.02 112.395 0) 
        (unit 1) 
        (in_bom yes) 
        (on_board yes) 
        (fields_autoplaced) 
        (property "Reference" "#PWR0101" 
            (id 0) 
            (at 168.91 114.935 0) 
            (effects 
                (font 
                    (size 1.27 1.27) 
                    (thickness 0.15)) 
                (justify left bottom) hide)) 
        (property "Value" "GND" 
            (id 1) 
            (at 160.02 116.8318 0) 
            (effects 
                (font 
                    (size 1.27 1.27) 
                    (thickness 0.15)) hide)) 
        (property "Footprint" "" 
            (id 2) 
            (at 168.91 120.015 0) 
            (effects 
                (font 
                    (size 1.27 1.27) 
                    (thickness 0.15)) 
                (justify left bottom) hide)) 
        (property "Datasheet" "" 
            (id 3) 
            (at 168.91 125.095 0) 
            (effects 
                (font 
                    (size 1.27 1.27) 
                    (thickness 0.15)) 
                (justify left bottom) hide)) 
        (property "Author" "Antmicro" 
            (id 4) 
            (at 168.91 120.015 0) 
            (effects 
                (font 
                    (size 1.27 1.27) 
                    (thickness 0.15)) 
                (justify left bottom) hide)) 
        (property "License" "Apache-2.0" 
            (id 5) 
            (at 168.91 122.555 0) 
            (effects 
                (font 
                    (size 1.27 1.27) 
                    (thickness 0.15)) 
                (justify left bottom) hide)) 
        (pin "1" 
           )) 
    (symbol 
        (lib_id "si-simulation-test-board:GND") 
        (at 128.27 82.55 0) 
        (unit 1) 
        (in_bom yes) 
        (on_board yes) 
        (fields_autoplaced) 
        (property "Reference" "#PWR0103" 
            (id 0) 
            (at 137.16 85.09 0) 
            (effects 
                (font 
                    (size 1.27 1.27) 
                    (thickness 0.15)) 
                (justify left bottom) hide)) 
        (property "Value" "GND" 
            (id 1) 
            (at 128.27 86.9868 0) 
            (effects 
                (font 
                    (size 1.27 1.27) 
                    (thickness 0.15)) hide)) 
        (property "Footprint" "" 
            (id 2) 
            (at 137.16 90.17 0) 
            (effects 
                (font 
                    (size 1.27 1.27) 
                    (thickness 0.15)) 
                (justify left bottom) hide)) 
        (property "Datasheet" "" 
            (id 3) 
            (at 137.16 95.25 0) 
            (effects 
                (font 
                    (size 1.27 1.27) 
                    (thickness 0.15)) 
                (justify left bottom) hide)) 
        (property "Author" "Antmicro" 
            (id 4) 
            (at 137.16 90.17 0) 
            (effects 
                (font 
                    (size 1.27 1.27) 
                    (thickness 0.15)) 
                (justify left bottom) hide)) 
        (property "License" "Apache-2.0" 
            (id 5) 
            (at 137.16 92.71 0) 
            (effects 
                (font 
                    (size 1.27 1.27) 
                    (thickness 0.15)) 
                (justify left bottom) hide)) 
        (pin "1" 
           )) 
    (symbol 
        (lib_id "si-simulation-test-board:Conn_SMA_RF2-143-T-17-50-G") 
        (at 116.205 75.565 0) 
        (mirror y) 
        (unit 1) 
        (in_bom yes) 
        (on_board yes) 
        (property "Reference" "J4" 
            (id 0) 
            (at 111.5059 70.0534 0) 
            (effects 
                (font 
                    (size 1.27 1.27) 
                    (thickness 0.15)))) 
        (property "Value" "Conn_SMA_RF2-143-T-17-50-G" 
            (id 1) 
            (at 91.44 75.565 0) 
            (effects 
                (font 
                    (size 1.27 1.27) 
                    (thickness 0.15)) hide)) 
        (property "Footprint" "si-simulation-test-board-footprints:RF_SMA_BoardEdge_RF2-143-T-17-50-G" 
            (id 2) 
            (at 95.885 85.725 0) 
            (effects 
                (font 
                    (size 1.27 1.27) 
                    (thickness 0.15)) 
                (justify left bottom) hide)) 
        (property "Datasheet" "https://www.tme.eu/Document/613028b507cfc72671e78c1d2ad14b1d/RF2-154-T-17-50-G.pdf" 
            (id 3) 
            (at 95.885 88.265 0) 
            (effects 
                (font 
                    (size 1.27 1.27) 
                    (thickness 0.15)) 
                (justify left bottom) hide)) 
        (property "MPN" "RF2-143-T-17-50-G" 
            (id 4) 
            (at 95.885 90.805 0) 
            (effects 
                (font 
                    (size 1.27 1.27) 
                    (thickness 0.15)) 
                (justify left bottom) hide)) 
        (property "Manufacturer" "ADAM TECH" 
            (id 5) 
            (at 95.885 93.345 0) 
            (effects 
                (font 
                    (size 1.27 1.27) 
                    (thickness 0.15)) 
                (justify left bottom) hide)) 
        (property "Author" "Antmicro" 
            (id 6) 
            (at 95.885 95.885 0) 
            (effects 
                (font 
                    (size 1.27 1.27) 
                    (thickness 0.15)) 
                (justify left bottom) hide)) 
        (property "License" "Apache-2.0" 
            (id 7) 
            (at 95.885 98.425 0) 
            (effects 
                (font 
                    (size 1.27 1.27) 
                    (thickness 0.15)) 
                (justify left bottom) hide)) 
        (pin "1" 
           ) 
        (pin "2" 
           )) 
    (symbol 
        (lib_id "si-simulation-test-board:Conn_SMA_RF2-143-T-17-50-G") 
        (at 184.15 126.365 0) 
        (unit 1) 
        (in_bom yes) 
        (on_board yes) 
        (fields_autoplaced) 
        (property "Reference" "J8" 
            (id 0) 
            (at 191.77 125.8911 0) 
            (effects 
                (font 
                    (size 1.27 1.27) 
                    (thickness 0.15)) 
                (justify left))) 
        (property "Value" "Conn_SMA_RF2-143-T-17-50-G" 
            (id 1) 
            (at 191.77 128.4148 0) 
            (effects 
                (font 
                    (size 1.27 1.27) 
                    (thickness 0.15)) 
                (justify left) hide)) 
        (property "Footprint" "si-simulation-test-board-footprints:RF_SMA_BoardEdge_RF2-143-T-17-50-G" 
            (id 2) 
            (at 204.47 136.525 0) 
            (effects 
                (font 
                    (size 1.27 1.27) 
                    (thickness 0.15)) 
                (justify left bottom) hide)) 
        (property "Datasheet" "https://www.tme.eu/Document/613028b507cfc72671e78c1d2ad14b1d/RF2-154-T-17-50-G.pdf" 
            (id 3) 
            (at 204.47 139.065 0) 
            (effects 
                (font 
                    (size 1.27 1.27) 
                    (thickness 0.15)) 
                (justify left bottom) hide)) 
        (property "MPN" "RF2-143-T-17-50-G" 
            (id 4) 
            (at 204.47 141.605 0) 
            (effects 
                (font 
                    (size 1.27 1.27) 
                    (thickness 0.15)) 
                (justify left bottom) hide)) 
        (property "Manufacturer" "ADAM TECH" 
            (id 5) 
            (at 204.47 144.145 0) 
            (effects 
                (font 
                    (size 1.27 1.27) 
                    (thickness 0.15)) 
                (justify left bottom) hide)) 
        (property "Author" "Antmicro" 
            (id 6) 
            (at 204.47 146.685 0) 
            (effects 
                (font 
                    (size 1.27 1.27) 
                    (thickness 0.15)) 
                (justify left bottom) hide)) 
        (property "License" "Apache-2.0" 
            (id 7) 
            (at 204.47 149.225 0) 
            (effects 
                (font 
                    (size 1.27 1.27) 
                    (thickness 0.15)) 
                (justify left bottom) hide)) 
        (pin "1" 
           ) 
        (pin "2" 
           )) 
    (symbol 
        (lib_id "si-simulation-test-board:R_0R_0201") 
        (at 176.53 153.67 180) 
        (unit 1) 
        (in_bom yes) 
        (on_board yes) 
        (property "Reference" "R4" 
            (id 0) 
            (at 168.91 152.4 0) 
            (effects 
                (font 
                    (size 1.27 1.27) 
                    (thickness 0.15)) 
                (justify right))) 
        (property "Value" "R_0R_0201" 
            (id 1) 
            (at 156.21 140.97 0) 
            (effects 
                (font 
                    (size 1.27 1.27) 
                    (thickness 0.15)) 
                (justify left bottom) hide)) 
        (property "Footprint" "si-simulation-test-board-footprints:R_0201" 
            (id 2) 
            (at 156.21 138.43 0) 
            (effects 
                (font 
                    (size 1.27 1.27) 
                    (thickness 0.15)) 
                (justify left bottom) hide)) 
        (property "Datasheet" "https://www.bourns.com/docs/product-datasheets/cr.pdf" 
            (id 3) 
            (at 156.21 135.89 0) 
            (effects 
                (font 
                    (size 1.27 1.27) 
                    (thickness 0.15)) 
                (justify left bottom) hide)) 
        (property "MPN" "CR0201-FX-0R00GLF" 
            (id 4) 
            (at 156.21 133.35 0) 
            (effects 
                (font 
                    (size 1.27 1.27) 
                    (thickness 0.15)) 
                (justify left bottom) hide)) 
        (property "Manufacturer" "Bourns" 
            (id 5) 
            (at 156.21 130.81 0) 
            (effects 
                (font 
                    (size 1.27 1.27) 
                    (thickness 0.15)) 
                (justify left bottom) hide)) 
        (property "License" "Apache-2.0" 
            (id 6) 
            (at 156.21 128.27 0) 
            (effects 
                (font 
                    (size 1.27 1.27) 
                    (thickness 0.15)) 
                (justify left bottom) hide)) 
        (property "Author" "Antmicro" 
            (id 7) 
            (at 156.21 125.73 0) 
            (effects 
                (font 
                    (size 1.27 1.27) 
                    (thickness 0.15)) 
                (justify left bottom) hide)) 
        (property "Val" "0R" 
            (id 8) 
            (at 168.91 154.94 0) 
            (effects 
                (font 
                    (size 1.27 1.27) 
                    (thickness 0.15)) 
                (justify right))) 
        (property "Tolerance" "1%" 
            (id 9) 
            (at 156.21 143.51 0) 
            (effects 
                (font 
                    (size 1.27 1.27)) 
                (justify left bottom) hide)) 
        (property "DNP" "DNP" 
            (id 10) 
            (at 173.99 153.67 0)) 
        (pin "1" 
           ) 
        (pin "2" 
           )) 
    (symbol 
        (lib_id "si-simulation-test-board:GND") 
        (at 179.197 267.97 0) 
        (unit 1) 
        (in_bom yes) 
        (on_board yes) 
        (fields_autoplaced) 
        (property "Reference" "#PWR0126" 
            (id 0) 
            (at 188.087 270.51 0) 
            (effects 
                (font 
                    (size 1.27 1.27) 
                    (thickness 0.15)) 
                (justify left bottom) hide)) 
        (property "Value" "GND" 
            (id 1) 
            (at 179.197 272.4068 0) 
            (effects 
                (font 
                    (size 1.27 1.27) 
                    (thickness 0.15)) hide)) 
        (property "Footprint" "" 
            (id 2) 
            (at 188.087 275.59 0) 
            (effects 
                (font 
                    (size 1.27 1.27) 
                    (thickness 0.15)) 
                (justify left bottom) hide)) 
        (property "Datasheet" "" 
            (id 3) 
            (at 188.087 280.67 0) 
            (effects 
                (font 
                    (size 1.27 1.27) 
                    (thickness 0.15)) 
                (justify left bottom) hide)) 
        (property "Author" "Antmicro" 
            (id 4) 
            (at 188.087 275.59 0) 
            (effects 
                (font 
                    (size 1.27 1.27) 
                    (thickness 0.15)) 
                (justify left bottom) hide)) 
        (property "License" "Apache-2.0" 
            (id 5) 
            (at 188.087 278.13 0) 
            (effects 
                (font 
                    (size 1.27 1.27) 
                    (thickness 0.15)) 
                (justify left bottom) hide)) 
        (pin "1" 
           )) 
    (symbol 
        (lib_id "si-simulation-test-board:GND") 
        (at 203.2 50.8 90) 
        (mirror x) 
        (unit 1) 
        (in_bom yes) 
        (on_board yes) 
        (fields_autoplaced) 
        (property "Reference" "#PWR0127" 
            (id 0) 
            (at 205.74 59.69 0) 
            (effects 
                (font 
                    (size 1.27 1.27) 
                    (thickness 0.15)) 
                (justify left bottom) hide)) 
        (property "Value" "GND" 
            (id 1) 
            (at 207.6368 50.8 0) 
            (effects 
                (font 
                    (size 1.27 1.27) 
                    (thickness 0.15)) hide)) 
        (property "Footprint" "" 
            (id 2) 
            (at 210.82 59.69 0) 
            (effects 
                (font 
                    (size 1.27 1.27) 
                    (thickness 0.15)) 
                (justify left bottom) hide)) 
        (property "Datasheet" "" 
            (id 3) 
            (at 215.9 59.69 0) 
            (effects 
                (font 
                    (size 1.27 1.27) 
                    (thickness 0.15)) 
                (justify left bottom) hide)) 
        (property "Author" "Antmicro" 
            (id 4) 
            (at 210.82 59.69 0) 
            (effects 
                (font 
                    (size 1.27 1.27) 
                    (thickness 0.15)) 
                (justify left bottom) hide)) 
        (property "License" "Apache-2.0" 
            (id 5) 
            (at 213.36 59.69 0) 
            (effects 
                (font 
                    (size 1.27 1.27) 
                    (thickness 0.15)) 
                (justify left bottom) hide)) 
        (pin "1" 
           )) 
    (symbol 
        (lib_id "si-simulation-test-board:GND") 
        (at 189.23 219.075 0) 
        (unit 1) 
        (in_bom yes) 
        (on_board yes) 
        (fields_autoplaced) 
        (property "Reference" "#PWR0124" 
            (id 0) 
            (at 198.12 221.615 0) 
            (effects 
                (font 
                    (size 1.27 1.27) 
                    (thickness 0.15)) 
                (justify left bottom) hide)) 
        (property "Value" "GND" 
            (id 1) 
            (at 189.23 223.5118 0) 
            (effects 
                (font 
                    (size 1.27 1.27) 
                    (thickness 0.15)) hide)) 
        (property "Footprint" "" 
            (id 2) 
            (at 198.12 226.695 0) 
            (effects 
                (font 
                    (size 1.27 1.27) 
                    (thickness 0.15)) 
                (justify left bottom) hide)) 
        (property "Datasheet" "" 
            (id 3) 
            (at 198.12 231.775 0) 
            (effects 
                (font 
                    (size 1.27 1.27) 
                    (thickness 0.15)) 
                (justify left bottom) hide)) 
        (property "Author" "Antmicro" 
            (id 4) 
            (at 198.12 226.695 0) 
            (effects 
                (font 
                    (size 1.27 1.27) 
                    (thickness 0.15)) 
                (justify left bottom) hide)) 
        (property "License" "Apache-2.0" 
            (id 5) 
            (at 198.12 229.235 0) 
            (effects 
                (font 
                    (size 1.27 1.27) 
                    (thickness 0.15)) 
                (justify left bottom) hide)) 
        (pin "1" 
           )) 
    (symbol 
        (lib_id "si-simulation-test-board:Conn_SMA_RF2-143-T-17-50-G") 
        (at 184.15 149.86 0) 
        (unit 1) 
        (in_bom yes) 
        (on_board yes) 
        (fields_autoplaced) 
        (property "Reference" "J10" 
            (id 0) 
            (at 191.77 149.3861 0) 
            (effects 
                (font 
                    (size 1.27 1.27) 
                    (thickness 0.15)) 
                (justify left))) 
        (property "Value" "Conn_SMA_RF2-143-T-17-50-G" 
            (id 1) 
            (at 191.77 151.9098 0) 
            (effects 
                (font 
                    (size 1.27 1.27) 
                    (thickness 0.15)) 
                (justify left) hide)) 
        (property "Footprint" "si-simulation-test-board-footprints:RF_SMA_BoardEdge_RF2-143-T-17-50-G" 
            (id 2) 
            (at 204.47 160.02 0) 
            (effects 
                (font 
                    (size 1.27 1.27) 
                    (thickness 0.15)) 
                (justify left bottom) hide)) 
        (property "Datasheet" "https://www.tme.eu/Document/613028b507cfc72671e78c1d2ad14b1d/RF2-154-T-17-50-G.pdf" 
            (id 3) 
            (at 204.47 162.56 0) 
            (effects 
                (font 
                    (size 1.27 1.27) 
                    (thickness 0.15)) 
                (justify left bottom) hide)) 
        (property "MPN" "RF2-143-T-17-50-G" 
            (id 4) 
            (at 204.47 165.1 0) 
            (effects 
                (font 
                    (size 1.27 1.27) 
                    (thickness 0.15)) 
                (justify left bottom) hide)) 
        (property "Manufacturer" "ADAM TECH" 
            (id 5) 
            (at 204.47 167.64 0) 
            (effects 
                (font 
                    (size 1.27 1.27) 
                    (thickness 0.15)) 
                (justify left bottom) hide)) 
        (property "Author" "Antmicro" 
            (id 6) 
            (at 204.47 170.18 0) 
            (effects 
                (font 
                    (size 1.27 1.27) 
                    (thickness 0.15)) 
                (justify left bottom) hide)) 
        (property "License" "Apache-2.0" 
            (id 7) 
            (at 204.47 172.72 0) 
            (effects 
                (font 
                    (size 1.27 1.27) 
                    (thickness 0.15)) 
                (justify left bottom) hide)) 
        (pin "1" 
           ) 
        (pin "2" 
           )) 
    (symbol 
        (lib_id "si-simulation-test-board:GND") 
        (at 189.23 133.35 0) 
        (unit 1) 
        (in_bom yes) 
        (on_board yes) 
        (fields_autoplaced) 
        (property "Reference" "#PWR0111" 
            (id 0) 
            (at 198.12 135.89 0) 
            (effects 
                (font 
                    (size 1.27 1.27) 
                    (thickness 0.15)) 
                (justify left bottom) hide)) 
        (property "Value" "GND" 
            (id 1) 
            (at 189.23 137.7868 0) 
            (effects 
                (font 
                    (size 1.27 1.27) 
                    (thickness 0.15)) hide)) 
        (property "Footprint" "" 
            (id 2) 
            (at 198.12 140.97 0) 
            (effects 
                (font 
                    (size 1.27 1.27) 
                    (thickness 0.15)) 
                (justify left bottom) hide)) 
        (property "Datasheet" "" 
            (id 3) 
            (at 198.12 146.05 0) 
            (effects 
                (font 
                    (size 1.27 1.27) 
                    (thickness 0.15)) 
                (justify left bottom) hide)) 
        (property "Author" "Antmicro" 
            (id 4) 
            (at 198.12 140.97 0) 
            (effects 
                (font 
                    (size 1.27 1.27) 
                    (thickness 0.15)) 
                (justify left bottom) hide)) 
        (property "License" "Apache-2.0" 
            (id 5) 
            (at 198.12 143.51 0) 
            (effects 
                (font 
                    (size 1.27 1.27) 
                    (thickness 0.15)) 
                (justify left bottom) hide)) 
        (pin "1" 
           )) 
    (symbol 
        (lib_id "si-simulation-test-board:Conn_SMA_RF2-143-T-17-50-G") 
        (at 164.465 189.23 0) 
        (mirror y) 
        (unit 1) 
        (in_bom yes) 
        (on_board yes) 
        (property "Reference" "J12" 
            (id 0) 
            (at 159.7659 183.7184 0) 
            (effects 
                (font 
                    (size 1.27 1.27) 
                    (thickness 0.15)))) 
        (property "Value" "Conn_SMA_RF2-143-T-17-50-G" 
            (id 1) 
            (at 139.7 189.23 0) 
            (effects 
                (font 
                    (size 1.27 1.27) 
                    (thickness 0.15)) hide)) 
        (property "Footprint" "si-simulation-test-board-footprints:RF_SMA_BoardEdge_RF2-143-T-17-50-G" 
            (id 2) 
            (at 144.145 199.39 0) 
            (effects 
                (font 
                    (size 1.27 1.27) 
                    (thickness 0.15)) 
                (justify left bottom) hide)) 
        (property "Datasheet" "https://www.tme.eu/Document/613028b507cfc72671e78c1d2ad14b1d/RF2-154-T-17-50-G.pdf" 
            (id 3) 
            (at 144.145 201.93 0) 
            (effects 
                (font 
                    (size 1.27 1.27) 
                    (thickness 0.15)) 
                (justify left bottom) hide)) 
        (property "MPN" "RF2-143-T-17-50-G" 
            (id 4) 
            (at 144.145 204.47 0) 
            (effects 
                (font 
                    (size 1.27 1.27) 
                    (thickness 0.15)) 
                (justify left bottom) hide)) 
        (property "Manufacturer" "ADAM TECH" 
            (id 5) 
            (at 144.145 207.01 0) 
            (effects 
                (font 
                    (size 1.27 1.27) 
                    (thickness 0.15)) 
                (justify left bottom) hide)) 
        (property "Author" "Antmicro" 
            (id 6) 
            (at 144.145 209.55 0) 
            (effects 
                (font 
                    (size 1.27 1.27) 
                    (thickness 0.15)) 
                (justify left bottom) hide)) 
        (property "License" "Apache-2.0" 
            (id 7) 
            (at 144.145 212.09 0) 
            (effects 
                (font 
                    (size 1.27 1.27) 
                    (thickness 0.15)) 
                (justify left bottom) hide)) 
        (pin "1" 
           ) 
        (pin "2" 
           )) 
    (symbol 
        (lib_id "si-simulation-test-board:GND") 
        (at 168.275 210.185 0) 
        (mirror x) 
        (unit 1) 
        (in_bom yes) 
        (on_board yes) 
        (fields_autoplaced) 
        (property "Reference" "#PWR0132" 
            (id 0) 
            (at 177.165 207.645 0) 
            (effects 
                (font 
                    (size 1.27 1.27) 
                    (thickness 0.15)) 
                (justify left bottom) hide)) 
        (property "Value" "GND" 
            (id 1) 
            (at 168.275 205.7482 0) 
            (effects 
                (font 
                    (size 1.27 1.27) 
                    (thickness 0.15)) hide)) 
        (property "Footprint" "" 
            (id 2) 
            (at 177.165 202.565 0) 
            (effects 
                (font 
                    (size 1.27 1.27) 
                    (thickness 0.15)) 
                (justify left bottom) hide)) 
        (property "Datasheet" "" 
            (id 3) 
            (at 177.165 197.485 0) 
            (effects 
                (font 
                    (size 1.27 1.27) 
                    (thickness 0.15)) 
                (justify left bottom) hide)) 
        (property "Author" "Antmicro" 
            (id 4) 
            (at 177.165 202.565 0) 
            (effects 
                (font 
                    (size 1.27 1.27) 
                    (thickness 0.15)) 
                (justify left bottom) hide)) 
        (property "License" "Apache-2.0" 
            (id 5) 
            (at 177.165 200.025 0) 
            (effects 
                (font 
                    (size 1.27 1.27) 
                    (thickness 0.15)) 
                (justify left bottom) hide)) 
        (pin "1" 
           )) 
    (symbol 
        (lib_id "si-simulation-test-board:GND") 
        (at 235.585 83.185 0) 
        (mirror y) 
        (unit 1) 
        (in_bom yes) 
        (on_board yes) 
        (fields_autoplaced) 
        (property "Reference" "#PWR0105" 
            (id 0) 
            (at 226.695 85.725 0) 
            (effects 
                (font 
                    (size 1.27 1.27) 
                    (thickness 0.15)) 
                (justify left bottom) hide)) 
        (property "Value" "GND" 
            (id 1) 
            (at 235.585 87.6218 0) 
            (effects 
                (font 
                    (size 1.27 1.27) 
                    (thickness 0.15)) hide)) 
        (property "Footprint" "" 
            (id 2) 
            (at 226.695 90.805 0) 
            (effects 
                (font 
                    (size 1.27 1.27) 
                    (thickness 0.15)) 
                (justify left bottom) hide)) 
        (property "Datasheet" "" 
            (id 3) 
            (at 226.695 95.885 0) 
            (effects 
                (font 
                    (size 1.27 1.27) 
                    (thickness 0.15)) 
                (justify left bottom) hide)) 
        (property "Author" "Antmicro" 
            (id 4) 
            (at 226.695 90.805 0) 
            (effects 
                (font 
                    (size 1.27 1.27) 
                    (thickness 0.15)) 
                (justify left bottom) hide)) 
        (property "License" "Apache-2.0" 
            (id 5) 
            (at 226.695 93.345 0) 
            (effects 
                (font 
                    (size 1.27 1.27) 
                    (thickness 0.15)) 
                (justify left bottom) hide)) 
        (pin "1" 
           )) 
    (symbol 
        (lib_id "si-simulation-test-board:Conn_SMA_RF2-143-T-17-50-G") 
        (at 184.15 255.27 0) 
        (unit 1) 
        (in_bom yes) 
        (on_board yes) 
        (fields_autoplaced) 
        (property "Reference" "J18" 
            (id 0) 
            (at 191.77 254.7961 0) 
            (effects 
                (font 
                    (size 1.27 1.27) 
                    (thickness 0.15)) 
                (justify left))) 
        (property "Value" "Conn_SMA_RF2-143-T-17-50-G" 
            (id 1) 
            (at 191.77 257.3198 0) 
            (effects 
                (font 
                    (size 1.27 1.27) 
                    (thickness 0.15)) 
                (justify left) hide)) 
        (property "Footprint" "si-simulation-test-board-footprints:RF_SMA_BoardEdge_RF2-143-T-17-50-G" 
            (id 2) 
            (at 204.47 265.43 0) 
            (effects 
                (font 
                    (size 1.27 1.27) 
                    (thickness 0.15)) 
                (justify left bottom) hide)) 
        (property "Datasheet" "https://www.tme.eu/Document/613028b507cfc72671e78c1d2ad14b1d/RF2-154-T-17-50-G.pdf" 
            (id 3) 
            (at 204.47 267.97 0) 
            (effects 
                (font 
                    (size 1.27 1.27) 
                    (thickness 0.15)) 
                (justify left bottom) hide)) 
        (property "MPN" "RF2-143-T-17-50-G" 
            (id 4) 
            (at 204.47 270.51 0) 
            (effects 
                (font 
                    (size 1.27 1.27) 
                    (thickness 0.15)) 
                (justify left bottom) hide)) 
        (property "Manufacturer" "ADAM TECH" 
            (id 5) 
            (at 204.47 273.05 0) 
            (effects 
                (font 
                    (size 1.27 1.27) 
                    (thickness 0.15)) 
                (justify left bottom) hide)) 
        (property "Author" "Antmicro" 
            (id 6) 
            (at 204.47 275.59 0) 
            (effects 
                (font 
                    (size 1.27 1.27) 
                    (thickness 0.15)) 
                (justify left bottom) hide)) 
        (property "License" "Apache-2.0" 
            (id 7) 
            (at 204.47 278.13 0) 
            (effects 
                (font 
                    (size 1.27 1.27) 
                    (thickness 0.15)) 
                (justify left bottom) hide)) 
        (pin "1" 
           ) 
        (pin "2" 
           )) 
    (symbol 
        (lib_id "si-simulation-test-board:GND") 
        (at 189.23 240.665 0) 
        (unit 1) 
        (in_bom yes) 
        (on_board yes) 
        (fields_autoplaced) 
        (property "Reference" "#PWR0120" 
            (id 0) 
            (at 198.12 243.205 0) 
            (effects 
                (font 
                    (size 1.27 1.27) 
                    (thickness 0.15)) 
                (justify left bottom) hide)) 
        (property "Value" "GND" 
            (id 1) 
            (at 189.23 245.1018 0) 
            (effects 
                (font 
                    (size 1.27 1.27) 
                    (thickness 0.15)) hide)) 
        (property "Footprint" "" 
            (id 2) 
            (at 198.12 248.285 0) 
            (effects 
                (font 
                    (size 1.27 1.27) 
                    (thickness 0.15)) 
                (justify left bottom) hide)) 
        (property "Datasheet" "" 
            (id 3) 
            (at 198.12 253.365 0) 
            (effects 
                (font 
                    (size 1.27 1.27) 
                    (thickness 0.15)) 
                (justify left bottom) hide)) 
        (property "Author" "Antmicro" 
            (id 4) 
            (at 198.12 248.285 0) 
            (effects 
                (font 
                    (size 1.27 1.27) 
                    (thickness 0.15)) 
                (justify left bottom) hide)) 
        (property "License" "Apache-2.0" 
            (id 5) 
            (at 198.12 250.825 0) 
            (effects 
                (font 
                    (size 1.27 1.27) 
                    (thickness 0.15)) 
                (justify left bottom) hide)) 
        (pin "1" 
           )) 
    (symbol 
        (lib_id "si-simulation-test-board:Conn_SMA_RF2-143-T-17-50-G") 
        (at 230.505 45.72 0) 
        (unit 1) 
        (in_bom yes) 
        (on_board yes) 
        (property "Reference" "J5" 
            (id 0) 
            (at 235.2041 40.2084 0) 
            (effects 
                (font 
                    (size 1.27 1.27) 
                    (thickness 0.15)))) 
        (property "Value" "Conn_SMA_RF2-143-T-17-50-G" 
            (id 1) 
            (at 255.27 45.72 0) 
            (effects 
                (font 
                    (size 1.27 1.27) 
                    (thickness 0.15)) hide)) 
        (property "Footprint" "si-simulation-test-board-footprints:RF_SMA_BoardEdge_RF2-143-T-17-50-G" 
            (id 2) 
            (at 250.825 55.88 0) 
            (effects 
                (font 
                    (size 1.27 1.27) 
                    (thickness 0.15)) 
                (justify left bottom) hide)) 
        (property "Datasheet" "https://www.tme.eu/Document/613028b507cfc72671e78c1d2ad14b1d/RF2-154-T-17-50-G.pdf" 
            (id 3) 
            (at 250.825 58.42 0) 
            (effects 
                (font 
                    (size 1.27 1.27) 
                    (thickness 0.15)) 
                (justify left bottom) hide)) 
        (property "MPN" "RF2-143-T-17-50-G" 
            (id 4) 
            (at 250.825 60.96 0) 
            (effects 
                (font 
                    (size 1.27 1.27) 
                    (thickness 0.15)) 
                (justify left bottom) hide)) 
        (property "Manufacturer" "ADAM TECH" 
            (id 5) 
            (at 250.825 63.5 0) 
            (effects 
                (font 
                    (size 1.27 1.27) 
                    (thickness 0.15)) 
                (justify left bottom) hide)) 
        (property "Author" "Antmicro" 
            (id 6) 
            (at 250.825 66.04 0) 
            (effects 
                (font 
                    (size 1.27 1.27) 
                    (thickness 0.15)) 
                (justify left bottom) hide)) 
        (property "License" "Apache-2.0" 
            (id 7) 
            (at 250.825 68.58 0) 
            (effects 
                (font 
                    (size 1.27 1.27) 
                    (thickness 0.15)) 
                (justify left bottom) hide)) 
        (pin "1" 
           ) 
        (pin "2" 
           )) 
    (symbol 
        (lib_id "si-simulation-test-board:GND") 
        (at 178.435 210.185 0) 
        (mirror x) 
        (unit 1) 
        (in_bom yes) 
        (on_board yes) 
        (fields_autoplaced) 
        (property "Reference" "#PWR0135" 
            (id 0) 
            (at 187.325 207.645 0) 
            (effects 
                (font 
                    (size 1.27 1.27) 
                    (thickness 0.15)) 
                (justify left bottom) hide)) 
        (property "Value" "GND" 
            (id 1) 
            (at 178.435 205.7482 0) 
            (effects 
                (font 
                    (size 1.27 1.27) 
                    (thickness 0.15)) hide)) 
        (property "Footprint" "" 
            (id 2) 
            (at 187.325 202.565 0) 
            (effects 
                (font 
                    (size 1.27 1.27) 
                    (thickness 0.15)) 
                (justify left bottom) hide)) 
        (property "Datasheet" "" 
            (id 3) 
            (at 187.325 197.485 0) 
            (effects 
                (font 
                    (size 1.27 1.27) 
                    (thickness 0.15)) 
                (justify left bottom) hide)) 
        (property "Author" "Antmicro" 
            (id 4) 
            (at 187.325 202.565 0) 
            (effects 
                (font 
                    (size 1.27 1.27) 
                    (thickness 0.15)) 
                (justify left bottom) hide)) 
        (property "License" "Apache-2.0" 
            (id 5) 
            (at 187.325 200.025 0) 
            (effects 
                (font 
                    (size 1.27 1.27) 
                    (thickness 0.15)) 
                (justify left bottom) hide)) 
        (pin "1" 
           )) 
    (symbol 
        (lib_id "si-simulation-test-board:GND") 
        (at 179.197 262.89 180) 
        (unit 1) 
        (in_bom yes) 
        (on_board yes) 
        (fields_autoplaced) 
        (property "Reference" "#PWR0131" 
            (id 0) 
            (at 170.307 260.35 0) 
            (effects 
                (font 
                    (size 1.27 1.27) 
                    (thickness 0.15)) 
                (justify left bottom) hide)) 
        (property "Value" "GND" 
            (id 1) 
            (at 181.102 262.0512 0) 
            (effects 
                (font 
                    (size 1.27 1.27) 
                    (thickness 0.15)) 
                (justify right) hide)) 
        (property "Footprint" "" 
            (id 2) 
            (at 170.307 255.27 0) 
            (effects 
                (font 
                    (size 1.27 1.27) 
                    (thickness 0.15)) 
                (justify left bottom) hide)) 
        (property "Datasheet" "" 
            (id 3) 
            (at 170.307 250.19 0) 
            (effects 
                (font 
                    (size 1.27 1.27) 
                    (thickness 0.15)) 
                (justify left bottom) hide)) 
        (property "Author" "Antmicro" 
            (id 4) 
            (at 170.307 255.27 0) 
            (effects 
                (font 
                    (size 1.27 1.27) 
                    (thickness 0.15)) 
                (justify left bottom) hide)) 
        (property "License" "Apache-2.0" 
            (id 5) 
            (at 170.307 252.73 0) 
            (effects 
                (font 
                    (size 1.27 1.27) 
                    (thickness 0.15)) 
                (justify left bottom) hide)) 
        (pin "1" 
           )) 
    (symbol 
        (lib_id "si-simulation-test-board:GND") 
        (at 149.86 50.8 270) 
        (unit 1) 
        (in_bom yes) 
        (on_board yes) 
        (fields_autoplaced) 
        (property "Reference" "#PWR0107" 
            (id 0) 
            (at 147.32 59.69 0) 
            (effects 
                (font 
                    (size 1.27 1.27) 
                    (thickness 0.15)) 
                (justify left bottom) hide)) 
        (property "Value" "GND" 
            (id 1) 
            (at 145.4232 50.8 0) 
            (effects 
                (font 
                    (size 1.27 1.27) 
                    (thickness 0.15)) hide)) 
        (property "Footprint" "" 
            (id 2) 
            (at 142.24 59.69 0) 
            (effects 
                (font 
                    (size 1.27 1.27) 
                    (thickness 0.15)) 
                (justify left bottom) hide)) 
        (property "Datasheet" "" 
            (id 3) 
            (at 137.16 59.69 0) 
            (effects 
                (font 
                    (size 1.27 1.27) 
                    (thickness 0.15)) 
                (justify left bottom) hide)) 
        (property "Author" "Antmicro" 
            (id 4) 
            (at 142.24 59.69 0) 
            (effects 
                (font 
                    (size 1.27 1.27) 
                    (thickness 0.15)) 
                (justify left bottom) hide)) 
        (property "License" "Apache-2.0" 
            (id 5) 
            (at 139.7 59.69 0) 
            (effects 
                (font 
                    (size 1.27 1.27) 
                    (thickness 0.15)) 
                (justify left bottom) hide)) 
        (pin "1" 
           )) 
    (symbol 
        (lib_id "si-simulation-test-board:Conn_SMA_RF2-143-T-17-50-G") 
        (at 164.465 149.86 0) 
        (mirror y) 
        (unit 1) 
        (in_bom yes) 
        (on_board yes) 
        (property "Reference" "J9" 
            (id 0) 
            (at 159.7659 144.3484 0) 
            (effects 
                (font 
                    (size 1.27 1.27) 
                    (thickness 0.15)))) 
        (property "Value" "Conn_SMA_RF2-143-T-17-50-G" 
            (id 1) 
            (at 139.7 149.86 0) 
            (effects 
                (font 
                    (size 1.27 1.27) 
                    (thickness 0.15)) hide)) 
        (property "Footprint" "si-simulation-test-board-footprints:RF_SMA_BoardEdge_RF2-143-T-17-50-G" 
            (id 2) 
            (at 144.145 160.02 0) 
            (effects 
                (font 
                    (size 1.27 1.27) 
                    (thickness 0.15)) 
                (justify left bottom) hide)) 
        (property "Datasheet" "https://www.tme.eu/Document/613028b507cfc72671e78c1d2ad14b1d/RF2-154-T-17-50-G.pdf" 
            (id 3) 
            (at 144.145 162.56 0) 
            (effects 
                (font 
                    (size 1.27 1.27) 
                    (thickness 0.15)) 
                (justify left bottom) hide)) 
        (property "MPN" "RF2-143-T-17-50-G" 
            (id 4) 
            (at 144.145 165.1 0) 
            (effects 
                (font 
                    (size 1.27 1.27) 
                    (thickness 0.15)) 
                (justify left bottom) hide)) 
        (property "Manufacturer" "ADAM TECH" 
            (id 5) 
            (at 144.145 167.64 0) 
            (effects 
                (font 
                    (size 1.27 1.27) 
                    (thickness 0.15)) 
                (justify left bottom) hide)) 
        (property "Author" "Antmicro" 
            (id 6) 
            (at 144.145 170.18 0) 
            (effects 
                (font 
                    (size 1.27 1.27) 
                    (thickness 0.15)) 
                (justify left bottom) hide)) 
        (property "License" "Apache-2.0" 
            (id 7) 
            (at 144.145 172.72 0) 
            (effects 
                (font 
                    (size 1.27 1.27) 
                    (thickness 0.15)) 
                (justify left bottom) hide)) 
        (pin "1" 
           ) 
        (pin "2" 
           )) 
    (symbol 
        (lib_id "si-simulation-test-board:GND") 
        (at 182.88 219.075 0) 
        (mirror y) 
        (unit 1) 
        (in_bom yes) 
        (on_board yes) 
        (fields_autoplaced) 
        (property "Reference" "#PWR0134" 
            (id 0) 
            (at 173.99 221.615 0) 
            (effects 
                (font 
                    (size 1.27 1.27) 
                    (thickness 0.15)) 
                (justify left bottom) hide)) 
        (property "Value" "GND" 
            (id 1) 
            (at 182.88 223.5118 0) 
            (effects 
                (font 
                    (size 1.27 1.27) 
                    (thickness 0.15)) hide)) 
        (property "Footprint" "" 
            (id 2) 
            (at 173.99 226.695 0) 
            (effects 
                (font 
                    (size 1.27 1.27) 
                    (thickness 0.15)) 
                (justify left bottom) hide)) 
        (property "Datasheet" "" 
            (id 3) 
            (at 173.99 231.775 0) 
            (effects 
                (font 
                    (size 1.27 1.27) 
                    (thickness 0.15)) 
                (justify left bottom) hide)) 
        (property "Author" "Antmicro" 
            (id 4) 
            (at 173.99 226.695 0) 
            (effects 
                (font 
                    (size 1.27 1.27) 
                    (thickness 0.15)) 
                (justify left bottom) hide)) 
        (property "License" "Apache-2.0" 
            (id 5) 
            (at 173.99 229.235 0) 
            (effects 
                (font 
                    (size 1.27 1.27) 
                    (thickness 0.15)) 
                (justify left bottom) hide)) 
        (pin "1" 
           )) 
    (symbol 
        (lib_id "si-simulation-test-board:GND") 
        (at 189.23 173.355 180) 
        (unit 1) 
        (in_bom yes) 
        (on_board yes) 
        (fields_autoplaced) 
        (property "Reference" "#PWR0119" 
            (id 0) 
            (at 180.34 170.815 0) 
            (effects 
                (font 
                    (size 1.27 1.27) 
                    (thickness 0.15)) 
                (justify left bottom) hide)) 
        (property "Value" "GND" 
            (id 1) 
            (at 189.23 168.9182 0) 
            (effects 
                (font 
                    (size 1.27 1.27) 
                    (thickness 0.15)) hide)) 
        (property "Footprint" "" 
            (id 2) 
            (at 180.34 165.735 0) 
            (effects 
                (font 
                    (size 1.27 1.27) 
                    (thickness 0.15)) 
                (justify left bottom) hide)) 
        (property "Datasheet" "" 
            (id 3) 
            (at 180.34 160.655 0) 
            (effects 
                (font 
                    (size 1.27 1.27) 
                    (thickness 0.15)) 
                (justify left bottom) hide)) 
        (property "Author" "Antmicro" 
            (id 4) 
            (at 180.34 165.735 0) 
            (effects 
                (font 
                    (size 1.27 1.27) 
                    (thickness 0.15)) 
                (justify left bottom) hide)) 
        (property "License" "Apache-2.0" 
            (id 5) 
            (at 180.34 163.195 0) 
            (effects 
                (font 
                    (size 1.27 1.27) 
                    (thickness 0.15)) 
                (justify left bottom) hide)) 
        (pin "1" 
           )) 
    (symbol 
        (lib_id "si-simulation-test-board:GND") 
        (at 167.005 267.97 0) 
        (unit 1) 
        (in_bom yes) 
        (on_board yes) 
        (fields_autoplaced) 
        (property "Reference" "#PWR0129" 
            (id 0) 
            (at 175.895 270.51 0) 
            (effects 
                (font 
                    (size 1.27 1.27) 
                    (thickness 0.15)) 
                (justify left bottom) hide)) 
        (property "Value" "GND" 
            (id 1) 
            (at 167.005 272.4068 0) 
            (effects 
                (font 
                    (size 1.27 1.27) 
                    (thickness 0.15)) hide)) 
        (property "Footprint" "" 
            (id 2) 
            (at 175.895 275.59 0) 
            (effects 
                (font 
                    (size 1.27 1.27) 
                    (thickness 0.15)) 
                (justify left bottom) hide)) 
        (property "Datasheet" "" 
            (id 3) 
            (at 175.895 280.67 0) 
            (effects 
                (font 
                    (size 1.27 1.27) 
                    (thickness 0.15)) 
                (justify left bottom) hide)) 
        (property "Author" "Antmicro" 
            (id 4) 
            (at 175.895 275.59 0) 
            (effects 
                (font 
                    (size 1.27 1.27) 
                    (thickness 0.15)) 
                (justify left bottom) hide)) 
        (property "License" "Apache-2.0" 
            (id 5) 
            (at 175.895 278.13 0) 
            (effects 
                (font 
                    (size 1.27 1.27) 
                    (thickness 0.15)) 
                (justify left bottom) hide)) 
        (pin "1" 
           )) 
    (symbol 
        (lib_id "si-simulation-test-board:R_0R_0201") 
        (at 182.88 131.445 180) 
        (unit 1) 
        (in_bom yes) 
        (on_board yes) 
        (property "Reference" "R3" 
            (id 0) 
            (at 174.625 130.175 0) 
            (effects 
                (font 
                    (size 1.27 1.27) 
                    (thickness 0.15)) 
                (justify right))) 
        (property "Value" "R_0R_0201" 
            (id 1) 
            (at 162.56 118.745 0) 
            (effects 
                (font 
                    (size 1.27 1.27) 
                    (thickness 0.15)) 
                (justify left bottom) hide)) 
        (property "Footprint" "si-simulation-test-board-footprints:R_0201" 
            (id 2) 
            (at 162.56 116.205 0) 
            (effects 
                (font 
                    (size 1.27 1.27) 
                    (thickness 0.15)) 
                (justify left bottom) hide)) 
        (property "Datasheet" "https://www.bourns.com/docs/product-datasheets/cr.pdf" 
            (id 3) 
            (at 162.56 113.665 0) 
            (effects 
                (font 
                    (size 1.27 1.27) 
                    (thickness 0.15)) 
                (justify left bottom) hide)) 
        (property "MPN" "CR0201-FX-0R00GLF" 
            (id 4) 
            (at 162.56 111.125 0) 
            (effects 
                (font 
                    (size 1.27 1.27) 
                    (thickness 0.15)) 
                (justify left bottom) hide)) 
        (property "Manufacturer" "Bourns" 
            (id 5) 
            (at 162.56 108.585 0) 
            (effects 
                (font 
                    (size 1.27 1.27) 
                    (thickness 0.15)) 
                (justify left bottom) hide)) 
        (property "License" "Apache-2.0" 
            (id 6) 
            (at 162.56 106.045 0) 
            (effects 
                (font 
                    (size 1.27 1.27) 
                    (thickness 0.15)) 
                (justify left bottom) hide)) 
        (property "Author" "Antmicro" 
            (id 7) 
            (at 162.56 103.505 0) 
            (effects 
                (font 
                    (size 1.27 1.27) 
                    (thickness 0.15)) 
                (justify left bottom) hide)) 
        (property "Val" "0R" 
            (id 8) 
            (at 174.625 132.715 0) 
            (effects 
                (font 
                    (size 1.27 1.27) 
                    (thickness 0.15)) 
                (justify right))) 
        (property "Tolerance" "1%" 
            (id 9) 
            (at 162.56 121.285 0) 
            (effects 
                (font 
                    (size 1.27 1.27)) 
                (justify left bottom) hide)) 
        (property "DNP" "DNP" 
            (id 10) 
            (at 180.34 131.445 0)) 
        (pin "1" 
           ) 
        (pin "2" 
           )) 
    (symbol 
        (lib_id "si-simulation-test-board:Conn_SMA_RF2-143-T-17-50-G") 
        (at 163.83 233.68 0) 
        (mirror y) 
        (unit 1) 
        (in_bom yes) 
        (on_board yes) 
        (property "Reference" "J15" 
            (id 0) 
            (at 159.1309 228.1684 0) 
            (effects 
                (font 
                    (size 1.27 1.27) 
                    (thickness 0.15)))) 
        (property "Value" "Conn_SMA_RF2-143-T-17-50-G" 
            (id 1) 
            (at 139.065 233.68 0) 
            (effects 
                (font 
                    (size 1.27 1.27) 
                    (thickness 0.15)) hide)) 
        (property "Footprint" "si-simulation-test-board-footprints:RF_SMA_BoardEdge_RF2-143-T-17-50-G" 
            (id 2) 
            (at 143.51 243.84 0) 
            (effects 
                (font 
                    (size 1.27 1.27) 
                    (thickness 0.15)) 
                (justify left bottom) hide)) 
        (property "Datasheet" "https://www.tme.eu/Document/613028b507cfc72671e78c1d2ad14b1d/RF2-154-T-17-50-G.pdf" 
            (id 3) 
            (at 143.51 246.38 0) 
            (effects 
                (font 
                    (size 1.27 1.27) 
                    (thickness 0.15)) 
                (justify left bottom) hide)) 
        (property "MPN" "RF2-143-T-17-50-G" 
            (id 4) 
            (at 143.51 248.92 0) 
            (effects 
                (font 
                    (size 1.27 1.27) 
                    (thickness 0.15)) 
                (justify left bottom) hide)) 
        (property "Manufacturer" "ADAM TECH" 
            (id 5) 
            (at 143.51 251.46 0) 
            (effects 
                (font 
                    (size 1.27 1.27) 
                    (thickness 0.15)) 
                (justify left bottom) hide)) 
        (property "Author" "Antmicro" 
            (id 6) 
            (at 143.51 254 0) 
            (effects 
                (font 
                    (size 1.27 1.27) 
                    (thickness 0.15)) 
                (justify left bottom) hide)) 
        (property "License" "Apache-2.0" 
            (id 7) 
            (at 143.51 256.54 0) 
            (effects 
                (font 
                    (size 1.27 1.27) 
                    (thickness 0.15)) 
                (justify left bottom) hide)) 
        (pin "1" 
           ) 
        (pin "2" 
           )) 
    (symbol 
        (lib_id "si-simulation-test-board:GND") 
        (at 189.23 196.215 0) 
        (unit 1) 
        (in_bom yes) 
        (on_board yes) 
        (fields_autoplaced) 
        (property "Reference" "#PWR0118" 
            (id 0) 
            (at 198.12 198.755 0) 
            (effects 
                (font 
                    (size 1.27 1.27) 
                    (thickness 0.15)) 
                (justify left bottom) hide)) 
        (property "Value" "GND" 
            (id 1) 
            (at 189.23 200.6518 0) 
            (effects 
                (font 
                    (size 1.27 1.27) 
                    (thickness 0.15)) hide)) 
        (property "Footprint" "" 
            (id 2) 
            (at 198.12 203.835 0) 
            (effects 
                (font 
                    (size 1.27 1.27) 
                    (thickness 0.15)) 
                (justify left bottom) hide)) 
        (property "Datasheet" "" 
            (id 3) 
            (at 198.12 208.915 0) 
            (effects 
                (font 
                    (size 1.27 1.27) 
                    (thickness 0.15)) 
                (justify left bottom) hide)) 
        (property "Author" "Antmicro" 
            (id 4) 
            (at 198.12 203.835 0) 
            (effects 
                (font 
                    (size 1.27 1.27) 
                    (thickness 0.15)) 
                (justify left bottom) hide)) 
        (property "License" "Apache-2.0" 
            (id 5) 
            (at 198.12 206.375 0) 
            (effects 
                (font 
                    (size 1.27 1.27) 
                    (thickness 0.15)) 
                (justify left bottom) hide)) 
        (pin "1" 
           )) 
    (symbol 
        (lib_id "si-simulation-test-board:C_100n_0402") 
        (at 167.005 267.97 90) 
        (unit 1) 
        (in_bom yes) 
        (on_board yes) 
        (fields_autoplaced) 
        (property "Reference" "C2" 
            (id 0) 
            (at 169.3291 264.593 90) 
            (effects 
                (font 
                    (size 1.27 1.27) 
                    (thickness 0.15)) 
                (justify right))) 
        (property "Value" "C_100n_0402" 
            (id 1) 
            (at 177.165 247.65 0) 
            (effects 
                (font 
                    (size 1.27 1.27) 
                    (thickness 0.15)) 
                (justify left bottom) hide)) 
        (property "Footprint" "si-simulation-test-board-footprints:C_0402_1005Metric" 
            (id 2) 
            (at 179.705 247.65 0) 
            (effects 
                (font 
                    (size 1.27 1.27) 
                    (thickness 0.15)) 
                (justify left bottom) hide)) 
        (property "Datasheet" "https://search.murata.co.jp/Ceramy/image/img/A01X/G101/ENG/GRM155R61H104KE14-01.pdf" 
            (id 3) 
            (at 182.245 247.65 0) 
            (effects 
                (font 
                    (size 1.27 1.27) 
                    (thickness 0.15)) 
                (justify left bottom) hide)) 
        (property "MPN" "GRM155R61H104KE14D" 
            (id 4) 
            (at 184.785 247.65 0) 
            (effects 
                (font 
                    (size 1.27 1.27) 
                    (thickness 0.15)) 
                (justify left bottom) hide)) 
        (property "Manufacturer" "Murata" 
            (id 5) 
            (at 187.325 247.65 0) 
            (effects 
                (font 
                    (size 1.27 1.27) 
                    (thickness 0.15)) 
                (justify left bottom) hide)) 
        (property "License" "Apache-2.0" 
            (id 6) 
            (at 189.865 247.65 0) 
            (effects 
                (font 
                    (size 1.27 1.27) 
                    (thickness 0.15)) 
                (justify left bottom) hide)) 
        (property "Author" "Antmicro" 
            (id 7) 
            (at 192.405 247.65 0) 
            (effects 
                (font 
                    (size 1.27 1.27) 
                    (thickness 0.15)) 
                (justify left bottom) hide)) 
        (property "Val" "100n" 
            (id 8) 
            (at 169.3291 267.1167 90) 
            (effects 
                (font 
                    (size 1.27 1.27) 
                    (thickness 0.15)) 
                (justify right))) 
        (property "Voltage" "50V" 
            (id 9) 
            (at 194.945 247.65 0) 
            (effects 
                (font 
                    (size 1.27 1.27)) 
                (justify left bottom) hide)) 
        (property "Dielectric" "X5R" 
            (id 10) 
            (at 197.485 247.65 0) 
            (effects 
                (font 
                    (size 1.27 1.27)) 
                (justify left bottom) hide)) 
        (pin "1" 
           ) 
        (pin "2" 
           )) 
    (symbol 
        (lib_id "si-simulation-test-board:Conn_SMA_RF2-143-T-17-50-G") 
        (at 164.465 180.34 180) 
        (unit 1) 
        (in_bom yes) 
        (on_board yes) 
        (fields_autoplaced) 
        (property "Reference" "J11" 
            (id 0) 
            (at 156.845 180.8139 0) 
            (effects 
                (font 
                    (size 1.27 1.27) 
                    (thickness 0.15)) 
                (justify left))) 
        (property "Value" "Conn_SMA_RF2-143-T-17-50-G" 
            (id 1) 
            (at 156.845 178.2902 0) 
            (effects 
                (font 
                    (size 1.27 1.27) 
                    (thickness 0.15)) 
                (justify left) hide)) 
        (property "Footprint" "si-simulation-test-board-footprints:RF_SMA_BoardEdge_RF2-143-T-17-50-G" 
            (id 2) 
            (at 144.145 170.18 0) 
            (effects 
                (font 
                    (size 1.27 1.27) 
                    (thickness 0.15)) 
                (justify left bottom) hide)) 
        (property "Datasheet" "https://www.tme.eu/Document/613028b507cfc72671e78c1d2ad14b1d/RF2-154-T-17-50-G.pdf" 
            (id 3) 
            (at 144.145 167.64 0) 
            (effects 
                (font 
                    (size 1.27 1.27) 
                    (thickness 0.15)) 
                (justify left bottom) hide)) 
        (property "MPN" "RF2-143-T-17-50-G" 
            (id 4) 
            (at 144.145 165.1 0) 
            (effects 
                (font 
                    (size 1.27 1.27) 
                    (thickness 0.15)) 
                (justify left bottom) hide)) 
        (property "Manufacturer" "ADAM TECH" 
            (id 5) 
            (at 144.145 162.56 0) 
            (effects 
                (font 
                    (size 1.27 1.27) 
                    (thickness 0.15)) 
                (justify left bottom) hide)) 
        (property "Author" "Antmicro" 
            (id 6) 
            (at 144.145 160.02 0) 
            (effects 
                (font 
                    (size 1.27 1.27) 
                    (thickness 0.15)) 
                (justify left bottom) hide)) 
        (property "License" "Apache-2.0" 
            (id 7) 
            (at 144.145 157.48 0) 
            (effects 
                (font 
                    (size 1.27 1.27) 
                    (thickness 0.15)) 
                (justify left bottom) hide)) 
        (pin "1" 
           ) 
        (pin "2" 
           )) 
    (symbol 
        (lib_id "si-simulation-test-board:Conn_SMA_RF2-143-T-17-50-G") 
        (at 156.845 55.88 270) 
        (mirror x) 
        (unit 1) 
        (in_bom yes) 
        (on_board yes) 
        (property "Reference" "J21" 
            (id 0) 
            (at 162.3566 51.1809 0) 
            (effects 
                (font 
                    (size 1.27 1.27) 
                    (thickness 0.15)))) 
        (property "Value" "Conn_SMA_RF2-143-T-17-50-G" 
            (id 1) 
            (at 156.845 31.115 0) 
            (effects 
                (font 
                    (size 1.27 1.27) 
                    (thickness 0.15)) hide)) 
        (property "Footprint" "si-simulation-test-board-footprints:RF_SMA_BoardEdge_RF2-143-T-17-50-G" 
            (id 2) 
            (at 146.685 35.56 0) 
            (effects 
                (font 
                    (size 1.27 1.27) 
                    (thickness 0.15)) 
                (justify left bottom) hide)) 
        (property "Datasheet" "https://www.tme.eu/Document/613028b507cfc72671e78c1d2ad14b1d/RF2-154-T-17-50-G.pdf" 
            (id 3) 
            (at 144.145 35.56 0) 
            (effects 
                (font 
                    (size 1.27 1.27) 
                    (thickness 0.15)) 
                (justify left bottom) hide)) 
        (property "MPN" "RF2-143-T-17-50-G" 
            (id 4) 
            (at 141.605 35.56 0) 
            (effects 
                (font 
                    (size 1.27 1.27) 
                    (thickness 0.15)) 
                (justify left bottom) hide)) 
        (property "Manufacturer" "ADAM TECH" 
            (id 5) 
            (at 139.065 35.56 0) 
            (effects 
                (font 
                    (size 1.27 1.27) 
                    (thickness 0.15)) 
                (justify left bottom) hide)) 
        (property "Author" "Antmicro" 
            (id 6) 
            (at 136.525 35.56 0) 
            (effects 
                (font 
                    (size 1.27 1.27) 
                    (thickness 0.15)) 
                (justify left bottom) hide)) 
        (property "License" "Apache-2.0" 
            (id 7) 
            (at 133.985 35.56 0) 
            (effects 
                (font 
                    (size 1.27 1.27) 
                    (thickness 0.15)) 
                (justify left bottom) hide)) 
        (pin "1" 
           ) 
        (pin "2" 
           )) 
    (symbol 
        (lib_id "si-simulation-test-board:Conn_SMA_RF2-143-T-17-50-G") 
        (at 163.83 212.09 0) 
        (mirror y) 
        (unit 1) 
        (in_bom yes) 
        (on_board yes) 
        (property "Reference" "J19" 
            (id 0) 
            (at 159.1309 206.5784 0) 
            (effects 
                (font 
                    (size 1.27 1.27) 
                    (thickness 0.15)))) 
        (property "Value" "Conn_SMA_RF2-143-T-17-50-G" 
            (id 1) 
            (at 139.065 212.09 0) 
            (effects 
                (font 
                    (size 1.27 1.27) 
                    (thickness 0.15)) hide)) 
        (property "Footprint" "si-simulation-test-board-footprints:RF_SMA_BoardEdge_RF2-143-T-17-50-G" 
            (id 2) 
            (at 143.51 222.25 0) 
            (effects 
                (font 
                    (size 1.27 1.27) 
                    (thickness 0.15)) 
                (justify left bottom) hide)) 
        (property "Datasheet" "https://www.tme.eu/Document/613028b507cfc72671e78c1d2ad14b1d/RF2-154-T-17-50-G.pdf" 
            (id 3) 
            (at 143.51 224.79 0) 
            (effects 
                (font 
                    (size 1.27 1.27) 
                    (thickness 0.15)) 
                (justify left bottom) hide)) 
        (property "MPN" "RF2-143-T-17-50-G" 
            (id 4) 
            (at 143.51 227.33 0) 
            (effects 
                (font 
                    (size 1.27 1.27) 
                    (thickness 0.15)) 
                (justify left bottom) hide)) 
        (property "Manufacturer" "ADAM TECH" 
            (id 5) 
            (at 143.51 229.87 0) 
            (effects 
                (font 
                    (size 1.27 1.27) 
                    (thickness 0.15)) 
                (justify left bottom) hide)) 
        (property "Author" "Antmicro" 
            (id 6) 
            (at 143.51 232.41 0) 
            (effects 
                (font 
                    (size 1.27 1.27) 
                    (thickness 0.15)) 
                (justify left bottom) hide)) 
        (property "License" "Apache-2.0" 
            (id 7) 
            (at 143.51 234.95 0) 
            (effects 
                (font 
                    (size 1.27 1.27) 
                    (thickness 0.15)) 
                (justify left bottom) hide)) 
        (pin "1" 
           ) 
        (pin "2" 
           )) 
    (symbol 
        (lib_id "si-simulation-test-board:GND") 
        (at 158.75 268.224 0) 
        (unit 1) 
        (in_bom yes) 
        (on_board yes) 
        (fields_autoplaced) 
        (property "Reference" "#PWR0122" 
            (id 0) 
            (at 167.64 270.764 0) 
            (effects 
                (font 
                    (size 1.27 1.27) 
                    (thickness 0.15)) 
                (justify left bottom) hide)) 
        (property "Value" "GND" 
            (id 1) 
            (at 158.75 272.6608 0) 
            (effects 
                (font 
                    (size 1.27 1.27) 
                    (thickness 0.15)) hide)) 
        (property "Footprint" "" 
            (id 2) 
            (at 167.64 275.844 0) 
            (effects 
                (font 
                    (size 1.27 1.27) 
                    (thickness 0.15)) 
                (justify left bottom) hide)) 
        (property "Datasheet" "" 
            (id 3) 
            (at 167.64 280.924 0) 
            (effects 
                (font 
                    (size 1.27 1.27) 
                    (thickness 0.15)) 
                (justify left bottom) hide)) 
        (property "Author" "Antmicro" 
            (id 4) 
            (at 167.64 275.844 0) 
            (effects 
                (font 
                    (size 1.27 1.27) 
                    (thickness 0.15)) 
                (justify left bottom) hide)) 
        (property "License" "Apache-2.0" 
            (id 5) 
            (at 167.64 278.384 0) 
            (effects 
                (font 
                    (size 1.27 1.27) 
                    (thickness 0.15)) 
                (justify left bottom) hide)) 
        (pin "1" 
           )) 
    (symbol 
        (lib_id "si-simulation-test-board:GND") 
        (at 177.165 153.67 90) 
        (unit 1) 
        (in_bom yes) 
        (on_board yes) 
        (fields_autoplaced) 
        (property "Reference" "#PWR0115" 
            (id 0) 
            (at 179.705 144.78 0) 
            (effects 
                (font 
                    (size 1.27 1.27) 
                    (thickness 0.15)) 
                (justify left bottom) hide)) 
        (property "Value" "GND" 
            (id 1) 
            (at 181.6018 153.67 0) 
            (effects 
                (font 
                    (size 1.27 1.27) 
                    (thickness 0.15)) hide)) 
        (property "Footprint" "" 
            (id 2) 
            (at 184.785 144.78 0) 
            (effects 
                (font 
                    (size 1.27 1.27) 
                    (thickness 0.15)) 
                (justify left bottom) hide)) 
        (property "Datasheet" "" 
            (id 3) 
            (at 189.865 144.78 0) 
            (effects 
                (font 
                    (size 1.27 1.27) 
                    (thickness 0.15)) 
                (justify left bottom) hide)) 
        (property "Author" "Antmicro" 
            (id 4) 
            (at 184.785 144.78 0) 
            (effects 
                (font 
                    (size 1.27 1.27) 
                    (thickness 0.15)) 
                (justify left bottom) hide)) 
        (property "License" "Apache-2.0" 
            (id 5) 
            (at 187.325 144.78 0) 
            (effects 
                (font 
                    (size 1.27 1.27) 
                    (thickness 0.15)) 
                (justify left bottom) hide)) 
        (pin "1" 
           )) 
    (symbol 
        (lib_id "si-simulation-test-board:Conn_SMA_RF2-143-T-17-50-G") 
        (at 196.215 55.88 90) 
        (unit 1) 
        (in_bom yes) 
        (on_board yes) 
        (property "Reference" "J22" 
            (id 0) 
            (at 190.7034 51.1809 0) 
            (effects 
                (font 
                    (size 1.27 1.27) 
                    (thickness 0.15)))) 
        (property "Value" "Conn_SMA_RF2-143-T-17-50-G" 
            (id 1) 
            (at 196.215 31.115 0) 
            (effects 
                (font 
                    (size 1.27 1.27) 
                    (thickness 0.15)) hide)) 
        (property "Footprint" "si-simulation-test-board-footprints:RF_SMA_BoardEdge_RF2-143-T-17-50-G" 
            (id 2) 
            (at 206.375 35.56 0) 
            (effects 
                (font 
                    (size 1.27 1.27) 
                    (thickness 0.15)) 
                (justify left bottom) hide)) 
        (property "Datasheet" "https://www.tme.eu/Document/613028b507cfc72671e78c1d2ad14b1d/RF2-154-T-17-50-G.pdf" 
            (id 3) 
            (at 208.915 35.56 0) 
            (effects 
                (font 
                    (size 1.27 1.27) 
                    (thickness 0.15)) 
                (justify left bottom) hide)) 
        (property "MPN" "RF2-143-T-17-50-G" 
            (id 4) 
            (at 211.455 35.56 0) 
            (effects 
                (font 
                    (size 1.27 1.27) 
                    (thickness 0.15)) 
                (justify left bottom) hide)) 
        (property "Manufacturer" "ADAM TECH" 
            (id 5) 
            (at 213.995 35.56 0) 
            (effects 
                (font 
                    (size 1.27 1.27) 
                    (thickness 0.15)) 
                (justify left bottom) hide)) 
        (property "Author" "Antmicro" 
            (id 6) 
            (at 216.535 35.56 0) 
            (effects 
                (font 
                    (size 1.27 1.27) 
                    (thickness 0.15)) 
                (justify left bottom) hide)) 
        (property "License" "Apache-2.0" 
            (id 7) 
            (at 219.075 35.56 0) 
            (effects 
                (font 
                    (size 1.27 1.27) 
                    (thickness 0.15)) 
                (justify left bottom) hide)) 
        (pin "1" 
           ) 
        (pin "2" 
           )) 
    (symbol 
        (lib_id "si-simulation-test-board:C_100n_0402") 
        (at 179.197 267.97 90) 
        (unit 1) 
        (in_bom yes) 
        (on_board yes) 
        (fields_autoplaced) 
        (property "Reference" "C1" 
            (id 0) 
            (at 181.5211 264.593 90) 
            (effects 
                (font 
                    (size 1.27 1.27) 
                    (thickness 0.15)) 
                (justify right))) 
        (property "Value" "C_100n_0402" 
            (id 1) 
            (at 189.357 247.65 0) 
            (effects 
                (font 
                    (size 1.27 1.27) 
                    (thickness 0.15)) 
                (justify left bottom) hide)) 
        (property "Footprint" "si-simulation-test-board-footprints:C_0402_1005Metric" 
            (id 2) 
            (at 191.897 247.65 0) 
            (effects 
                (font 
                    (size 1.27 1.27) 
                    (thickness 0.15)) 
                (justify left bottom) hide)) 
        (property "Datasheet" "https://search.murata.co.jp/Ceramy/image/img/A01X/G101/ENG/GRM155R61H104KE14-01.pdf" 
            (id 3) 
            (at 194.437 247.65 0) 
            (effects 
                (font 
                    (size 1.27 1.27) 
                    (thickness 0.15)) 
                (justify left bottom) hide)) 
        (property "MPN" "GRM155R61H104KE14D" 
            (id 4) 
            (at 196.977 247.65 0) 
            (effects 
                (font 
                    (size 1.27 1.27) 
                    (thickness 0.15)) 
                (justify left bottom) hide)) 
        (property "Manufacturer" "Murata" 
            (id 5) 
            (at 199.517 247.65 0) 
            (effects 
                (font 
                    (size 1.27 1.27) 
                    (thickness 0.15)) 
                (justify left bottom) hide)) 
        (property "License" "Apache-2.0" 
            (id 6) 
            (at 202.057 247.65 0) 
            (effects 
                (font 
                    (size 1.27 1.27) 
                    (thickness 0.15)) 
                (justify left bottom) hide)) 
        (property "Author" "Antmicro" 
            (id 7) 
            (at 204.597 247.65 0) 
            (effects 
                (font 
                    (size 1.27 1.27) 
                    (thickness 0.15)) 
                (justify left bottom) hide)) 
        (property "Val" "100n" 
            (id 8) 
            (at 181.5211 267.1167 90) 
            (effects 
                (font 
                    (size 1.27 1.27) 
                    (thickness 0.15)) 
                (justify right))) 
        (property "Voltage" "50V" 
            (id 9) 
            (at 207.137 247.65 0) 
            (effects 
                (font 
                    (size 1.27 1.27)) 
                (justify left bottom) hide)) 
        (property "Dielectric" "X5R" 
            (id 10) 
            (at 209.677 247.65 0) 
            (effects 
                (font 
                    (size 1.27 1.27)) 
                (justify left bottom) hide)) 
        (pin "1" 
           ) 
        (pin "2" 
           )) 
    (symbol 
        (lib_id "si-simulation-test-board:GND") 
        (at 189.23 267.97 0) 
        (unit 1) 
        (in_bom yes) 
        (on_board yes) 
        (fields_autoplaced) 
        (property "Reference" "#PWR0121" 
            (id 0) 
            (at 198.12 270.51 0) 
            (effects 
                (font 
                    (size 1.27 1.27) 
                    (thickness 0.15)) 
                (justify left bottom) hide)) 
        (property "Value" "GND" 
            (id 1) 
            (at 189.23 272.4068 0) 
            (effects 
                (font 
                    (size 1.27 1.27) 
                    (thickness 0.15)) hide)) 
        (property "Footprint" "" 
            (id 2) 
            (at 198.12 275.59 0) 
            (effects 
                (font 
                    (size 1.27 1.27) 
                    (thickness 0.15)) 
                (justify left bottom) hide)) 
        (property "Datasheet" "" 
            (id 3) 
            (at 198.12 280.67 0) 
            (effects 
                (font 
                    (size 1.27 1.27) 
                    (thickness 0.15)) 
                (justify left bottom) hide)) 
        (property "Author" "Antmicro" 
            (id 4) 
            (at 198.12 275.59 0) 
            (effects 
                (font 
                    (size 1.27 1.27) 
                    (thickness 0.15)) 
                (justify left bottom) hide)) 
        (property "License" "Apache-2.0" 
            (id 5) 
            (at 198.12 278.13 0) 
            (effects 
                (font 
                    (size 1.27 1.27) 
                    (thickness 0.15)) 
                (justify left bottom) hide)) 
        (pin "1" 
           )) 
    (symbol 
        (lib_id "si-simulation-test-board:Conn_SMA_RF2-143-T-17-50-G") 
        (at 165.1 105.41 0) 
        (mirror y) 
        (unit 1) 
        (in_bom yes) 
        (on_board yes) 
        (property "Reference" "J1" 
            (id 0) 
            (at 156.21 105.41 0) 
            (effects 
                (font 
                    (size 1.27 1.27) 
                    (thickness 0.15)))) 
        (property "Value" "Conn_SMA_RF2-143-T-17-50-G" 
            (id 1) 
            (at 140.335 105.41 0) 
            (effects 
                (font 
                    (size 1.27 1.27) 
                    (thickness 0.15)) hide)) 
        (property "Footprint" "si-simulation-test-board-footprints:RF_SMA_BoardEdge_RF2-143-T-17-50-G" 
            (id 2) 
            (at 144.78 115.57 0) 
            (effects 
                (font 
                    (size 1.27 1.27) 
                    (thickness 0.15)) 
                (justify left bottom) hide)) 
        (property "Datasheet" "https://www.tme.eu/Document/613028b507cfc72671e78c1d2ad14b1d/RF2-154-T-17-50-G.pdf" 
            (id 3) 
            (at 144.78 118.11 0) 
            (effects 
                (font 
                    (size 1.27 1.27) 
                    (thickness 0.15)) 
                (justify left bottom) hide)) 
        (property "MPN" "RF2-143-T-17-50-G" 
            (id 4) 
            (at 144.78 120.65 0) 
            (effects 
                (font 
                    (size 1.27 1.27) 
                    (thickness 0.15)) 
                (justify left bottom) hide)) 
        (property "Manufacturer" "ADAM TECH" 
            (id 5) 
            (at 144.78 123.19 0) 
            (effects 
                (font 
                    (size 1.27 1.27) 
                    (thickness 0.15)) 
                (justify left bottom) hide)) 
        (property "Author" "Antmicro" 
            (id 6) 
            (at 144.78 125.73 0) 
            (effects 
                (font 
                    (size 1.27 1.27) 
                    (thickness 0.15)) 
                (justify left bottom) hide)) 
        (property "License" "Apache-2.0" 
            (id 7) 
            (at 144.78 128.27 0) 
            (effects 
                (font 
                    (size 1.27 1.27) 
                    (thickness 0.15)) 
                (justify left bottom) hide)) 
        (pin "1" 
           ) 
        (pin "2" 
           )) 
    (symbol 
        (lib_id "si-simulation-test-board:GND") 
        (at 158.75 219.075 0) 
        (unit 1) 
        (in_bom yes) 
        (on_board yes) 
        (fields_autoplaced) 
        (property "Reference" "#PWR0125" 
            (id 0) 
            (at 167.64 221.615 0) 
            (effects 
                (font 
                    (size 1.27 1.27) 
                    (thickness 0.15)) 
                (justify left bottom) hide)) 
        (property "Value" "GND" 
            (id 1) 
            (at 158.75 223.5118 0) 
            (effects 
                (font 
                    (size 1.27 1.27) 
                    (thickness 0.15)) hide)) 
        (property "Footprint" "" 
            (id 2) 
            (at 167.64 226.695 0) 
            (effects 
                (font 
                    (size 1.27 1.27) 
                    (thickness 0.15)) 
                (justify left bottom) hide)) 
        (property "Datasheet" "" 
            (id 3) 
            (at 167.64 231.775 0) 
            (effects 
                (font 
                    (size 1.27 1.27) 
                    (thickness 0.15)) 
                (justify left bottom) hide)) 
        (property "Author" "Antmicro" 
            (id 4) 
            (at 167.64 226.695 0) 
            (effects 
                (font 
                    (size 1.27 1.27) 
                    (thickness 0.15)) 
                (justify left bottom) hide)) 
        (property "License" "Apache-2.0" 
            (id 5) 
            (at 167.64 229.235 0) 
            (effects 
                (font 
                    (size 1.27 1.27) 
                    (thickness 0.15)) 
                (justify left bottom) hide)) 
        (pin "1" 
           )) 
    (sheet_instances 
        (path "/" 
            (page "1"))) 
    (symbol_instances 
        (path "" 
            (reference "#PWR0101") 
            (unit 1) 
            (value "GND") 
            (footprint "")) 
        (path "" 
            (reference "#PWR0102") 
            (unit 1) 
            (value "GND") 
            (footprint "")) 
        (path "" 
            (reference "#PWR0103") 
            (unit 1) 
            (value "GND") 
            (footprint "")) 
        (path "" 
            (reference "#PWR0104") 
            (unit 1) 
            (value "GND") 
            (footprint "")) 
        (path "" 
            (reference "#PWR0105") 
            (unit 1) 
            (value "GND") 
            (footprint "")) 
        (path "" 
            (reference "#PWR0106") 
            (unit 1) 
            (value "GND") 
            (footprint "")) 
        (path "" 
            (reference "#PWR0107") 
            (unit 1) 
            (value "GND") 
            (footprint "")) 
        (path "" 
            (reference "#PWR0108") 
            (unit 1) 
            (value "GND") 
            (footprint "")) 
        (path "" 
            (reference "#PWR0109") 
            (unit 1) 
            (value "GND") 
            (footprint "")) 
        (path "" 
            (reference "#PWR0110") 
            (unit 1) 
            (value "GND") 
            (footprint "")) 
        (path "" 
            (reference "#PWR0111") 
            (unit 1) 
            (value "GND") 
            (footprint "")) 
        (path "" 
            (reference "#PWR0112") 
            (unit 1) 
            (value "GND") 
            (footprint "")) 
        (path "" 
            (reference "#PWR0113") 
            (unit 1) 
            (value "GND") 
            (footprint "")) 
        (path "" 
            (reference "#PWR0114") 
            (unit 1) 
            (value "GND") 
            (footprint "")) 
        (path "" 
            (reference "#PWR0115") 
            (unit 1) 
            (value "GND") 
            (footprint "")) 
        (path "" 
            (reference "#PWR0116") 
            (unit 1) 
            (value "GND") 
            (footprint "")) 
        (path "" 
            (reference "#PWR0117") 
            (unit 1) 
            (value "GND") 
            (footprint "")) 
        (path "" 
            (reference "#PWR0118") 
            (unit 1) 
            (value "GND") 
            (footprint "")) 
        (path "" 
            (reference "#PWR0119") 
            (unit 1) 
            (value "GND") 
            (footprint "")) 
        (path "" 
            (reference "#PWR0120") 
            (unit 1) 
            (value "GND") 
            (footprint "")) 
        (path "" 
            (reference "#PWR0121") 
            (unit 1) 
            (value "GND") 
            (footprint "")) 
        (path "" 
            (reference "#PWR0122") 
            (unit 1) 
            (value "GND") 
            (footprint "")) 
        (path "" 
            (reference "#PWR0123") 
            (unit 1) 
            (value "GND") 
            (footprint "")) 
        (path "" 
            (reference "#PWR0124") 
            (unit 1) 
            (value "GND") 
            (footprint "")) 
        (path "" 
            (reference "#PWR0125") 
            (unit 1) 
            (value "GND") 
            (footprint "")) 
        (path "" 
            (reference "#PWR0126") 
            (unit 1) 
            (value "GND") 
            (footprint "")) 
        (path "" 
            (reference "#PWR0127") 
            (unit 1) 
            (value "GND") 
            (footprint "")) 
        (path "" 
            (reference "#PWR0128") 
            (unit 1) 
            (value "GND") 
            (footprint "")) 
        (path "" 
            (reference "#PWR0129") 
            (unit 1) 
            (value "GND") 
            (footprint "")) 
        (path "" 
            (reference "#PWR0130") 
            (unit 1) 
            (value "GND") 
            (footprint "")) 
        (path "" 
            (reference "#PWR0131") 
            (unit 1) 
            (value "GND") 
            (footprint "")) 
        (path "" 
            (reference "#PWR0132") 
            (unit 1) 
            (value "GND") 
            (footprint "")) 
        (path "" 
            (reference "#PWR0133") 
            (unit 1) 
            (value "GND") 
            (footprint "")) 
        (path "" 
            (reference "#PWR0134") 
            (unit 1) 
            (value "GND") 
            (footprint "")) 
        (path "" 
            (reference "#PWR0135") 
            (unit 1) 
            (value "GND") 
            (footprint "")) 
        (path "" 
            (reference "AE1") 
            (unit 1) 
            (value "Antenna") 
            (footprint "")) 
        (path "" 
            (reference "C1") 
            (unit 1) 
            (value "C_100n_0402") 
            (footprint "si-simulation-test-board-footprints:C_0402_1005Metric")) 
        (path "" 
            (reference "C2") 
            (unit 1) 
            (value "C_100n_0402") 
            (footprint "si-simulation-test-board-footprints:C_0402_1005Metric")) 
        (path "" 
            (reference "J1") 
            (unit 1) 
            (value "Conn_SMA_RF2-143-T-17-50-G") 
            (footprint "si-simulation-test-board-footprints:RF_SMA_BoardEdge_RF2-143-T-17-50-G")) 
        (path "" 
            (reference "J2") 
            (unit 1) 
            (value "Conn_SMA_RF2-143-T-17-50-G") 
            (footprint "si-simulation-test-board-footprints:RF_SMA_BoardEdge_RF2-143-T-17-50-G")) 
        (path "" 
            (reference "J3") 
            (unit 1) 
            (value "Conn_SMA_RF2-143-T-17-50-G") 
            (footprint "si-simulation-test-board-footprints:RF_SMA_BoardEdge_RF2-143-T-17-50-G")) 
        (path "" 
            (reference "J4") 
            (unit 1) 
            (value "Conn_SMA_RF2-143-T-17-50-G") 
            (footprint "si-simulation-test-board-footprints:RF_SMA_BoardEdge_RF2-143-T-17-50-G")) 
        (path "" 
            (reference "J5") 
            (unit 1) 
            (value "Conn_SMA_RF2-143-T-17-50-G") 
            (footprint "si-simulation-test-board-footprints:RF_SMA_BoardEdge_RF2-143-T-17-50-G")) 
        (path "" 
            (reference "J6") 
            (unit 1) 
            (value "Conn_SMA_RF2-143-T-17-50-G") 
            (footprint "si-simulation-test-board-footprints:RF_SMA_BoardEdge_RF2-143-T-17-50-G")) 
        (path "" 
            (reference "J7") 
            (unit 1) 
            (value "Conn_SMA_RF2-143-T-17-50-G") 
            (footprint "si-simulation-test-board-footprints:RF_SMA_BoardEdge_RF2-143-T-17-50-G")) 
        (path "" 
            (reference "J8") 
            (unit 1) 
            (value "Conn_SMA_RF2-143-T-17-50-G") 
            (footprint "si-simulation-test-board-footprints:RF_SMA_BoardEdge_RF2-143-T-17-50-G")) 
        (path "" 
            (reference "J9") 
            (unit 1) 
            (value "Conn_SMA_RF2-143-T-17-50-G") 
            (footprint "si-simulation-test-board-footprints:RF_SMA_BoardEdge_RF2-143-T-17-50-G")) 
        (path "" 
            (reference "J10") 
            (unit 1) 
            (value "Conn_SMA_RF2-143-T-17-50-G") 
            (footprint "si-simulation-test-board-footprints:RF_SMA_BoardEdge_RF2-143-T-17-50-G")) 
        (path "" 
            (reference "J11") 
            (unit 1) 
            (value "Conn_SMA_RF2-143-T-17-50-G") 
            (footprint "si-simulation-test-board-footprints:RF_SMA_BoardEdge_RF2-143-T-17-50-G")) 
        (path "" 
            (reference "J12") 
            (unit 1) 
            (value "Conn_SMA_RF2-143-T-17-50-G") 
            (footprint "si-simulation-test-board-footprints:RF_SMA_BoardEdge_RF2-143-T-17-50-G")) 
        (path "" 
            (reference "J13") 
            (unit 1) 
            (value "Conn_SMA_RF2-143-T-17-50-G") 
            (footprint "si-simulation-test-board-footprints:RF_SMA_BoardEdge_RF2-143-T-17-50-G")) 
        (path "" 
            (reference "J14") 
            (unit 1) 
            (value "Conn_SMA_RF2-143-T-17-50-G") 
            (footprint "si-simulation-test-board-footprints:RF_SMA_BoardEdge_RF2-143-T-17-50-G")) 
        (path "" 
            (reference "J15") 
            (unit 1) 
            (value "Conn_SMA_RF2-143-T-17-50-G") 
            (footprint "si-simulation-test-board-footprints:RF_SMA_BoardEdge_RF2-143-T-17-50-G")) 
        (path "" 
            (reference "J16") 
            (unit 1) 
            (value "Conn_SMA_RF2-143-T-17-50-G") 
            (footprint "si-simulation-test-board-footprints:RF_SMA_BoardEdge_RF2-143-T-17-50-G")) 
        (path "" 
            (reference "J17") 
            (unit 1) 
            (value "Conn_SMA_RF2-143-T-17-50-G") 
            (footprint "si-simulation-test-board-footprints:RF_SMA_BoardEdge_RF2-143-T-17-50-G")) 
        (path "" 
            (reference "J18") 
            (unit 1) 
            (value "Conn_SMA_RF2-143-T-17-50-G") 
            (footprint "si-simulation-test-board-footprints:RF_SMA_BoardEdge_RF2-143-T-17-50-G")) 
        (path "" 
            (reference "J19") 
            (unit 1) 
            (value "Conn_SMA_RF2-143-T-17-50-G") 
            (footprint "si-simulation-test-board-footprints:RF_SMA_BoardEdge_RF2-143-T-17-50-G")) 
        (path "" 
            (reference "J20") 
            (unit 1) 
            (value "Conn_SMA_RF2-143-T-17-50-G") 
            (footprint "si-simulation-test-board-footprints:RF_SMA_BoardEdge_RF2-143-T-17-50-G")) 
        (path "" 
            (reference "J21") 
            (unit 1) 
            (value "Conn_SMA_RF2-143-T-17-50-G") 
            (footprint "si-simulation-test-board-footprints:RF_SMA_BoardEdge_RF2-143-T-17-50-G")) 
        (path "" 
            (reference "J22") 
            (unit 1) 
            (value "Conn_SMA_RF2-143-T-17-50-G") 
            (footprint "si-simulation-test-board-footprints:RF_SMA_BoardEdge_RF2-143-T-17-50-G")) 
        (path "" 
            (reference "R2") 
            (unit 1) 
            (value "R_50R_0402") 
            (footprint "si-simulation-test-board-footprints:R_0402_1005Metric")) 
        (path "" 
            (reference "R3") 
            (unit 1) 
            (value "R_0R_0201") 
            (footprint "si-simulation-test-board-footprints:R_0201")) 
        (path "" 
            (reference "R4") 
            (unit 1) 
            (value "R_0R_0201") 
            (footprint "si-simulation-test-board-footprints:R_0201"))))
